(kicad_sch
	(version 20250114)
	(generator "eeschema")
	(generator_version "9.0")
	(paper "A3")
	(title_block
		(title "RDIMM DDR5 Tester")
		(date "2026-05-21")
		(rev "2.2.0")
		(company "Antmicro")
		(comment 1 "www.antmicro.com")
		(comment 2 "Antmicro")
	)
	(text "+1V8"
		(exclude_from_sim no)
		(at 134.62 129.54 0)
		(effects
			(font
				(size 1.27 1.27)
			)
			(justify left bottom)
		)
	)
	(text "NOTE:\noptional \nexternal divider "
		(exclude_from_sim no)
		(at 241.3 79.375 0)
		(effects
			(font
				(size 1.27 1.27)
			)
			(justify left bottom)
		)
	)
	(text "X"
		(exclude_from_sim no)
		(at 149.86 129.54 0)
		(effects
			(font
				(size 1.27 1.27)
			)
			(justify left bottom)
		)
	)
	(text "MGTAVTT"
		(exclude_from_sim no)
		(at 134.62 132.08 0)
		(effects
			(font
				(size 1.27 1.27)
			)
			(justify left bottom)
		)
	)
	(text "I2C: 0x4D"
		(exclude_from_sim no)
		(at 250.19 224.79 0)
		(effects
			(font
				(size 1.27 1.27)
			)
			(justify left bottom)
		)
	)
	(text "NOTE:\noptional \nexternal divider "
		(exclude_from_sim no)
		(at 271.78 107.315 0)
		(effects
			(font
				(size 1.27 1.27)
			)
			(justify left bottom)
		)
	)
	(text "X"
		(exclude_from_sim no)
		(at 154.305 134.62 0)
		(effects
			(font
				(size 1.27 1.27)
			)
			(justify left bottom)
		)
	)
	(text "X"
		(exclude_from_sim no)
		(at 159.385 132.08 0)
		(effects
			(font
				(size 1.27 1.27)
			)
			(justify left bottom)
		)
	)
	(text "NOTE:\noptional \nexternal divider "
		(exclude_from_sim no)
		(at 271.145 79.375 0)
		(effects
			(font
				(size 1.27 1.27)
			)
			(justify left bottom)
		)
	)
	(text "I2C: 0x18"
		(exclude_from_sim no)
		(at 163.83 224.79 0)
		(effects
			(font
				(size 1.27 1.27)
			)
			(justify left bottom)
		)
	)
	(text "Current sense monitors"
		(exclude_from_sim no)
		(at 17.78 160.02 0)
		(effects
			(font
				(size 2 2)
				(thickness 0.6)
				(bold yes)
			)
			(justify left bottom)
		)
	)
	(text "X"
		(exclude_from_sim no)
		(at 164.465 137.16 0)
		(effects
			(font
				(size 1.27 1.27)
			)
			(justify left bottom)
		)
	)
	(text "NOTE:\noptional \nexternal divider "
		(exclude_from_sim no)
		(at 241.3 107.315 0)
		(effects
			(font
				(size 1.27 1.27)
			)
			(justify left bottom)
		)
	)
	(text "DC-DC AUX, MGT"
		(exclude_from_sim no)
		(at 16.51 20.32 0)
		(effects
			(font
				(size 3 3)
				(thickness 0.6)
				(bold yes)
			)
			(justify left bottom)
		)
	)
	(text "1	2	3	4"
		(exclude_from_sim no)
		(at 149.86 127 0)
		(effects
			(font
				(size 1.27 1.27)
			)
			(justify left bottom)
		)
	)
	(text "Soft start delay time slot"
		(exclude_from_sim no)
		(at 138.43 123.19 0)
		(effects
			(font
				(size 1.27 1.27)
			)
			(justify left bottom)
		)
	)
	(text "MGTAVCCAUX"
		(exclude_from_sim no)
		(at 134.62 137.16 0)
		(effects
			(font
				(size 1.27 1.27)
			)
			(justify left bottom)
		)
	)
	(text "I2C: 0x68"
		(exclude_from_sim no)
		(at 153.035 110.49 0)
		(effects
			(font
				(size 1.27 1.27)
			)
			(justify left bottom)
		)
	)
	(text "MGTAVCC"
		(exclude_from_sim no)
		(at 134.62 134.62 0)
		(effects
			(font
				(size 1.27 1.27)
			)
			(justify left bottom)
		)
	)
	(junction
		(at 240.03 215.9)
		(diameter 0)
		(color 0 0 0 0)
	)
	(junction
		(at 222.25 74.93)
		(diameter 0)
		(color 0 0 0 0)
	)
	(junction
		(at 229.87 53.34)
		(diameter 0)
		(color 0 0 0 0)
	)
	(junction
		(at 185.42 74.93)
		(diameter 0)
		(color 0 0 0 0)
	)
	(junction
		(at 229.87 111.76)
		(diameter 0)
		(color 0 0 0 0)
	)
	(junction
		(at 124.46 52.07)
		(diameter 0)
		(color 0 0 0 0)
	)
	(junction
		(at 222.25 53.34)
		(diameter 0)
		(color 0 0 0 0)
	)
	(junction
		(at 209.55 53.34)
		(diameter 0)
		(color 0 0 0 0)
	)
	(junction
		(at 114.3 60.96)
		(diameter 0)
		(color 0 0 0 0)
	)
	(junction
		(at 184.15 53.34)
		(diameter 0)
		(color 0 0 0 0)
	)
	(junction
		(at 217.17 92.71)
		(diameter 0)
		(color 0 0 0 0)
	)
	(junction
		(at 229.87 74.93)
		(diameter 0)
		(color 0 0 0 0)
	)
	(junction
		(at 114.3 52.07)
		(diameter 0)
		(color 0 0 0 0)
	)
	(junction
		(at 217.17 53.34)
		(diameter 0)
		(color 0 0 0 0)
	)
	(junction
		(at 240.03 217.17)
		(diameter 0)
		(color 0 0 0 0)
	)
	(junction
		(at 220.98 92.71)
		(diameter 0)
		(color 0 0 0 0)
	)
	(junction
		(at 288.29 71.12)
		(diameter 0)
		(color 0 0 0 0)
	)
	(junction
		(at 176.53 53.34)
		(diameter 0)
		(color 0 0 0 0)
	)
	(junction
		(at 209.55 74.93)
		(diameter 0)
		(color 0 0 0 0)
	)
	(junction
		(at 222.25 193.04)
		(diameter 0)
		(color 0 0 0 0)
	)
	(junction
		(at 289.56 99.06)
		(diameter 0)
		(color 0 0 0 0)
	)
	(junction
		(at 153.67 217.17)
		(diameter 0)
		(color 0 0 0 0)
	)
	(junction
		(at 185.42 53.34)
		(diameter 0)
		(color 0 0 0 0)
	)
	(junction
		(at 259.08 99.06)
		(diameter 0)
		(color 0 0 0 0)
	)
	(junction
		(at 209.55 92.71)
		(diameter 0)
		(color 0 0 0 0)
	)
	(junction
		(at 153.67 215.9)
		(diameter 0)
		(color 0 0 0 0)
	)
	(junction
		(at 176.53 63.5)
		(diameter 0)
		(color 0 0 0 0)
	)
	(junction
		(at 259.08 71.12)
		(diameter 0)
		(color 0 0 0 0)
	)
	(junction
		(at 229.87 92.71)
		(diameter 0)
		(color 0 0 0 0)
	)
	(junction
		(at 185.42 92.71)
		(diameter 0)
		(color 0 0 0 0)
	)
	(junction
		(at 185.42 85.09)
		(diameter 0)
		(color 0 0 0 0)
	)
	(junction
		(at 185.42 111.76)
		(diameter 0)
		(color 0 0 0 0)
	)
	(junction
		(at 222.25 111.76)
		(diameter 0)
		(color 0 0 0 0)
	)
	(junction
		(at 185.42 63.5)
		(diameter 0)
		(color 0 0 0 0)
	)
	(junction
		(at 217.17 111.76)
		(diameter 0)
		(color 0 0 0 0)
	)
	(junction
		(at 135.89 193.04)
		(diameter 0)
		(color 0 0 0 0)
	)
	(junction
		(at 217.17 74.93)
		(diameter 0)
		(color 0 0 0 0)
	)
	(junction
		(at 176.53 74.93)
		(diameter 0)
		(color 0 0 0 0)
	)
	(junction
		(at 185.42 102.87)
		(diameter 0)
		(color 0 0 0 0)
	)
	(junction
		(at 209.55 111.76)
		(diameter 0)
		(color 0 0 0 0)
	)
	(no_connect
		(at 165.1 72.39)
	)
	(no_connect
		(at 165.1 85.09)
	)
	(wire
		(pts
			(xy 185.42 92.71) (xy 209.55 92.71)
		)
		(stroke
			(width 0)
			(type default)
		)
	)
	(wire
		(pts
			(xy 271.78 219.71) (xy 271.78 220.98)
		)
		(stroke
			(width 0)
			(type default)
		)
	)
	(wire
		(pts
			(xy 171.45 77.47) (xy 171.45 63.5)
		)
		(stroke
			(width 0)
			(type default)
		)
	)
	(wire
		(pts
			(xy 135.89 88.9) (xy 137.16 88.9)
		)
		(stroke
			(width 0)
			(type default)
		)
	)
	(wire
		(pts
			(xy 240.03 213.36) (xy 240.03 215.9)
		)
		(stroke
			(width 0)
			(type default)
		)
	)
	(wire
		(pts
			(xy 114.3 52.07) (xy 114.3 54.61)
		)
		(stroke
			(width 0)
			(type default)
		)
	)
	(wire
		(pts
			(xy 217.17 60.96) (xy 229.87 60.96)
		)
		(stroke
			(width 0)
			(type default)
		)
	)
	(wire
		(pts
			(xy 259.08 88.9) (xy 259.08 91.44)
		)
		(stroke
			(width 0)
			(type default)
		)
	)
	(wire
		(pts
			(xy 185.42 60.96) (xy 185.42 63.5)
		)
		(stroke
			(width 0)
			(type default)
		)
	)
	(wire
		(pts
			(xy 259.08 99.06) (xy 259.08 101.6)
		)
		(stroke
			(width 0)
			(type default)
		)
	)
	(wire
		(pts
			(xy 166.37 53.34) (xy 176.53 53.34)
		)
		(stroke
			(width 0)
			(type default)
		)
	)
	(wire
		(pts
			(xy 217.17 100.33) (xy 233.68 100.33)
		)
		(stroke
			(width 0)
			(type default)
		)
	)
	(wire
		(pts
			(xy 135.89 105.41) (xy 137.16 105.41)
		)
		(stroke
			(width 0)
			(type default)
		)
	)
	(polyline
		(pts
			(xy 157.48 124.46) (xy 157.48 137.16)
		)
		(stroke
			(width 0)
			(type default)
		)
	)
	(wire
		(pts
			(xy 135.89 195.58) (xy 135.89 193.04)
		)
		(stroke
			(width 0)
			(type default)
		)
	)
	(polyline
		(pts
			(xy 167.64 129.54) (xy 167.64 132.08)
		)
		(stroke
			(width 0)
			(type default)
		)
	)
	(polyline
		(pts
			(xy 241.3 72.39) (xy 241.3 81.28)
		)
		(stroke
			(width 0)
			(type default)
		)
	)
	(wire
		(pts
			(xy 241.3 215.9) (xy 240.03 215.9)
		)
		(stroke
			(width 0)
			(type default)
		)
	)
	(wire
		(pts
			(xy 229.87 90.17) (xy 229.87 92.71)
		)
		(stroke
			(width 0)
			(type default)
		)
	)
	(wire
		(pts
			(xy 114.3 59.69) (xy 114.3 60.96)
		)
		(stroke
			(width 0)
			(type default)
		)
	)
	(wire
		(pts
			(xy 146.05 215.9) (xy 146.05 217.17)
		)
		(stroke
			(width 0)
			(type default)
		)
	)
	(polyline
		(pts
			(xy 167.64 129.54) (xy 167.64 120.65)
		)
		(stroke
			(width 0)
			(type default)
		)
	)
	(wire
		(pts
			(xy 153.67 213.36) (xy 153.67 215.9)
		)
		(stroke
			(width 0)
			(type default)
		)
	)
	(wire
		(pts
			(xy 209.55 111.76) (xy 210.82 111.76)
		)
		(stroke
			(width 0)
			(type default)
		)
	)
	(polyline
		(pts
			(xy 134.62 129.54) (xy 167.64 129.54)
		)
		(stroke
			(width 0)
			(type default)
		)
	)
	(wire
		(pts
			(xy 222.25 190.5) (xy 222.25 193.04)
		)
		(stroke
			(width 0)
			(type default)
		)
	)
	(wire
		(pts
			(xy 229.87 92.71) (xy 232.41 92.71)
		)
		(stroke
			(width 0)
			(type default)
		)
	)
	(wire
		(pts
			(xy 252.73 99.06) (xy 259.08 99.06)
		)
		(stroke
			(width 0)
			(type default)
		)
	)
	(wire
		(pts
			(xy 153.67 196.85) (xy 154.94 196.85)
		)
		(stroke
			(width 0)
			(type default)
		)
	)
	(wire
		(pts
			(xy 288.29 78.74) (xy 288.29 81.28)
		)
		(stroke
			(width 0)
			(type default)
		)
	)
	(wire
		(pts
			(xy 185.42 74.93) (xy 209.55 74.93)
		)
		(stroke
			(width 0)
			(type default)
		)
	)
	(polyline
		(pts
			(xy 298.45 100.33) (xy 298.45 109.22)
		)
		(stroke
			(width 0)
			(type default)
		)
	)
	(polyline
		(pts
			(xy 270.51 72.39) (xy 270.51 81.28)
		)
		(stroke
			(width 0)
			(type default)
		)
	)
	(wire
		(pts
			(xy 165.1 87.63) (xy 168.91 87.63)
		)
		(stroke
			(width 0)
			(type default)
		)
	)
	(wire
		(pts
			(xy 176.53 53.34) (xy 176.53 55.88)
		)
		(stroke
			(width 0)
			(type default)
		)
	)
	(wire
		(pts
			(xy 240.03 196.85) (xy 241.3 196.85)
		)
		(stroke
			(width 0)
			(type default)
		)
	)
	(wire
		(pts
			(xy 165.1 105.41) (xy 168.91 105.41)
		)
		(stroke
			(width 0)
			(type default)
		)
	)
	(polyline
		(pts
			(xy 147.32 124.46) (xy 147.32 125.73)
		)
		(stroke
			(width 0)
			(type default)
		)
	)
	(wire
		(pts
			(xy 168.91 74.93) (xy 165.1 74.93)
		)
		(stroke
			(width 0)
			(type default)
		)
	)
	(wire
		(pts
			(xy 176.53 60.96) (xy 176.53 63.5)
		)
		(stroke
			(width 0)
			(type default)
		)
	)
	(wire
		(pts
			(xy 137.16 52.07) (xy 137.16 69.85)
		)
		(stroke
			(width 0)
			(type default)
		)
	)
	(polyline
		(pts
			(xy 134.62 134.62) (xy 167.64 134.62)
		)
		(stroke
			(width 0)
			(type default)
		)
	)
	(wire
		(pts
			(xy 154.94 213.36) (xy 153.67 213.36)
		)
		(stroke
			(width 0)
			(type default)
		)
	)
	(wire
		(pts
			(xy 232.41 215.9) (xy 232.41 217.17)
		)
		(stroke
			(width 0)
			(type default)
		)
	)
	(wire
		(pts
			(xy 266.7 195.58) (xy 285.75 195.58)
		)
		(stroke
			(width 0)
			(type default)
		)
	)
	(polyline
		(pts
			(xy 298.45 72.39) (xy 298.45 81.28)
		)
		(stroke
			(width 0)
			(type default)
		)
	)
	(wire
		(pts
			(xy 284.48 99.06) (xy 289.56 99.06)
		)
		(stroke
			(width 0)
			(type default)
		)
	)
	(wire
		(pts
			(xy 184.15 53.34) (xy 185.42 53.34)
		)
		(stroke
			(width 0)
			(type default)
		)
	)
	(wire
		(pts
			(xy 222.25 111.76) (xy 229.87 111.76)
		)
		(stroke
			(width 0)
			(type default)
		)
	)
	(wire
		(pts
			(xy 217.17 100.33) (xy 217.17 99.06)
		)
		(stroke
			(width 0)
			(type default)
		)
	)
	(wire
		(pts
			(xy 232.41 209.55) (xy 232.41 210.82)
		)
		(stroke
			(width 0)
			(type default)
		)
	)
	(wire
		(pts
			(xy 229.87 74.93) (xy 231.14 74.93)
		)
		(stroke
			(width 0)
			(type default)
		)
	)
	(wire
		(pts
			(xy 222.25 201.93) (xy 241.3 201.93)
		)
		(stroke
			(width 0)
			(type default)
		)
	)
	(wire
		(pts
			(xy 153.67 215.9) (xy 153.67 217.17)
		)
		(stroke
			(width 0)
			(type default)
		)
	)
	(wire
		(pts
			(xy 266.7 199.39) (xy 285.75 199.39)
		)
		(stroke
			(width 0)
			(type default)
		)
	)
	(wire
		(pts
			(xy 114.3 50.8) (xy 114.3 52.07)
		)
		(stroke
			(width 0)
			(type default)
		)
	)
	(wire
		(pts
			(xy 209.55 92.71) (xy 210.82 92.71)
		)
		(stroke
			(width 0)
			(type default)
		)
	)
	(wire
		(pts
			(xy 176.53 102.87) (xy 176.53 111.76)
		)
		(stroke
			(width 0)
			(type default)
		)
	)
	(polyline
		(pts
			(xy 269.24 72.39) (xy 269.24 81.28)
		)
		(stroke
			(width 0)
			(type default)
		)
	)
	(polyline
		(pts
			(xy 271.78 100.33) (xy 271.78 109.22)
		)
		(stroke
			(width 0)
			(type default)
		)
	)
	(polyline
		(pts
			(xy 270.51 72.39) (xy 298.45 72.39)
		)
		(stroke
			(width 0)
			(type default)
		)
	)
	(wire
		(pts
			(xy 266.7 193.04) (xy 285.75 193.04)
		)
		(stroke
			(width 0)
			(type default)
		)
	)
	(wire
		(pts
			(xy 220.98 92.71) (xy 229.87 92.71)
		)
		(stroke
			(width 0)
			(type default)
		)
	)
	(wire
		(pts
			(xy 180.34 193.04) (xy 199.39 193.04)
		)
		(stroke
			(width 0)
			(type default)
		)
	)
	(wire
		(pts
			(xy 279.4 88.9) (xy 289.56 88.9)
		)
		(stroke
			(width 0)
			(type default)
		)
	)
	(polyline
		(pts
			(xy 167.64 137.16) (xy 167.64 132.08)
		)
		(stroke
			(width 0)
			(type default)
		)
	)
	(wire
		(pts
			(xy 165.1 69.85) (xy 166.37 69.85)
		)
		(stroke
			(width 0)
			(type default)
		)
	)
	(wire
		(pts
			(xy 217.17 59.69) (xy 217.17 60.96)
		)
		(stroke
			(width 0)
			(type default)
		)
	)
	(wire
		(pts
			(xy 185.42 119.38) (xy 185.42 120.65)
		)
		(stroke
			(width 0)
			(type default)
		)
	)
	(wire
		(pts
			(xy 229.87 53.34) (xy 229.87 48.26)
		)
		(stroke
			(width 0)
			(type default)
		)
	)
	(wire
		(pts
			(xy 185.42 63.5) (xy 185.42 64.77)
		)
		(stroke
			(width 0)
			(type default)
		)
	)
	(wire
		(pts
			(xy 165.1 82.55) (xy 173.99 82.55)
		)
		(stroke
			(width 0)
			(type default)
		)
	)
	(wire
		(pts
			(xy 259.08 60.96) (xy 259.08 63.5)
		)
		(stroke
			(width 0)
			(type default)
		)
	)
	(wire
		(pts
			(xy 289.56 99.06) (xy 289.56 101.6)
		)
		(stroke
			(width 0)
			(type default)
		)
	)
	(polyline
		(pts
			(xy 298.45 81.28) (xy 270.51 81.28)
		)
		(stroke
			(width 0)
			(type default)
		)
	)
	(wire
		(pts
			(xy 222.25 201.93) (xy 222.25 200.66)
		)
		(stroke
			(width 0)
			(type default)
		)
	)
	(wire
		(pts
			(xy 217.17 118.11) (xy 217.17 124.46)
		)
		(stroke
			(width 0)
			(type default)
		)
	)
	(wire
		(pts
			(xy 135.89 201.93) (xy 135.89 200.66)
		)
		(stroke
			(width 0)
			(type default)
		)
	)
	(wire
		(pts
			(xy 209.55 82.55) (xy 193.04 82.55)
		)
		(stroke
			(width 0)
			(type default)
		)
	)
	(wire
		(pts
			(xy 154.94 209.55) (xy 146.05 209.55)
		)
		(stroke
			(width 0)
			(type default)
		)
	)
	(wire
		(pts
			(xy 120.65 72.39) (xy 137.16 72.39)
		)
		(stroke
			(width 0)
			(type default)
		)
	)
	(wire
		(pts
			(xy 209.55 100.33) (xy 193.04 100.33)
		)
		(stroke
			(width 0)
			(type default)
		)
	)
	(wire
		(pts
			(xy 176.53 74.93) (xy 185.42 74.93)
		)
		(stroke
			(width 0)
			(type default)
		)
	)
	(wire
		(pts
			(xy 279.4 60.96) (xy 288.29 60.96)
		)
		(stroke
			(width 0)
			(type default)
		)
	)
	(wire
		(pts
			(xy 266.7 201.93) (xy 285.75 201.93)
		)
		(stroke
			(width 0)
			(type default)
		)
	)
	(wire
		(pts
			(xy 153.67 199.39) (xy 154.94 199.39)
		)
		(stroke
			(width 0)
			(type default)
		)
	)
	(wire
		(pts
			(xy 165.1 102.87) (xy 176.53 102.87)
		)
		(stroke
			(width 0)
			(type default)
		)
	)
	(wire
		(pts
			(xy 114.3 52.07) (xy 124.46 52.07)
		)
		(stroke
			(width 0)
			(type default)
		)
	)
	(wire
		(pts
			(xy 215.9 111.76) (xy 217.17 111.76)
		)
		(stroke
			(width 0)
			(type default)
		)
	)
	(wire
		(pts
			(xy 222.25 52.07) (xy 222.25 53.34)
		)
		(stroke
			(width 0)
			(type default)
		)
	)
	(wire
		(pts
			(xy 222.25 195.58) (xy 222.25 193.04)
		)
		(stroke
			(width 0)
			(type default)
		)
	)
	(polyline
		(pts
			(xy 152.4 124.46) (xy 152.4 137.16)
		)
		(stroke
			(width 0)
			(type default)
		)
	)
	(wire
		(pts
			(xy 124.46 52.07) (xy 137.16 52.07)
		)
		(stroke
			(width 0)
			(type default)
		)
	)
	(wire
		(pts
			(xy 259.08 106.68) (xy 259.08 109.22)
		)
		(stroke
			(width 0)
			(type default)
		)
	)
	(wire
		(pts
			(xy 215.9 92.71) (xy 217.17 92.71)
		)
		(stroke
			(width 0)
			(type default)
		)
	)
	(wire
		(pts
			(xy 217.17 124.46) (xy 238.76 124.46)
		)
		(stroke
			(width 0)
			(type default)
		)
	)
	(wire
		(pts
			(xy 217.17 81.28) (xy 217.17 82.55)
		)
		(stroke
			(width 0)
			(type default)
		)
	)
	(wire
		(pts
			(xy 222.25 74.93) (xy 229.87 74.93)
		)
		(stroke
			(width 0)
			(type default)
		)
	)
	(wire
		(pts
			(xy 135.89 105.41) (xy 135.89 106.68)
		)
		(stroke
			(width 0)
			(type default)
		)
	)
	(wire
		(pts
			(xy 135.89 193.04) (xy 154.94 193.04)
		)
		(stroke
			(width 0)
			(type default)
		)
	)
	(wire
		(pts
			(xy 185.42 85.09) (xy 185.42 86.36)
		)
		(stroke
			(width 0)
			(type default)
		)
	)
	(wire
		(pts
			(xy 166.37 53.34) (xy 166.37 69.85)
		)
		(stroke
			(width 0)
			(type default)
		)
	)
	(wire
		(pts
			(xy 180.34 102.87) (xy 185.42 102.87)
		)
		(stroke
			(width 0)
			(type default)
		)
	)
	(wire
		(pts
			(xy 217.17 92.71) (xy 220.98 92.71)
		)
		(stroke
			(width 0)
			(type default)
		)
	)
	(wire
		(pts
			(xy 232.41 217.17) (xy 240.03 217.17)
		)
		(stroke
			(width 0)
			(type default)
		)
	)
	(wire
		(pts
			(xy 180.34 201.93) (xy 199.39 201.93)
		)
		(stroke
			(width 0)
			(type default)
		)
	)
	(wire
		(pts
			(xy 229.87 71.12) (xy 229.87 74.93)
		)
		(stroke
			(width 0)
			(type default)
		)
	)
	(wire
		(pts
			(xy 243.84 60.96) (xy 259.08 60.96)
		)
		(stroke
			(width 0)
			(type default)
		)
	)
	(wire
		(pts
			(xy 217.17 111.76) (xy 222.25 111.76)
		)
		(stroke
			(width 0)
			(type default)
		)
	)
	(wire
		(pts
			(xy 289.56 106.68) (xy 289.56 110.49)
		)
		(stroke
			(width 0)
			(type default)
		)
	)
	(wire
		(pts
			(xy 240.03 215.9) (xy 240.03 217.17)
		)
		(stroke
			(width 0)
			(type default)
		)
	)
	(polyline
		(pts
			(xy 241.3 100.33) (xy 267.97 100.33)
		)
		(stroke
			(width 0)
			(type default)
		)
	)
	(polyline
		(pts
			(xy 147.32 125.73) (xy 147.32 137.16)
		)
		(stroke
			(width 0)
			(type default)
		)
	)
	(wire
		(pts
			(xy 229.87 111.76) (xy 232.41 111.76)
		)
		(stroke
			(width 0)
			(type default)
		)
	)
	(wire
		(pts
			(xy 254 71.12) (xy 259.08 71.12)
		)
		(stroke
			(width 0)
			(type default)
		)
	)
	(wire
		(pts
			(xy 217.17 82.55) (xy 233.68 82.55)
		)
		(stroke
			(width 0)
			(type default)
		)
	)
	(wire
		(pts
			(xy 135.89 190.5) (xy 135.89 193.04)
		)
		(stroke
			(width 0)
			(type default)
		)
	)
	(wire
		(pts
			(xy 171.45 63.5) (xy 176.53 63.5)
		)
		(stroke
			(width 0)
			(type default)
		)
	)
	(wire
		(pts
			(xy 176.53 74.93) (xy 176.53 77.47)
		)
		(stroke
			(width 0)
			(type default)
		)
	)
	(wire
		(pts
			(xy 222.25 73.66) (xy 222.25 74.93)
		)
		(stroke
			(width 0)
			(type default)
		)
	)
	(polyline
		(pts
			(xy 267.97 109.22) (xy 241.3 109.22)
		)
		(stroke
			(width 0)
			(type default)
		)
	)
	(wire
		(pts
			(xy 217.17 53.34) (xy 222.25 53.34)
		)
		(stroke
			(width 0)
			(type default)
		)
	)
	(wire
		(pts
			(xy 259.08 96.52) (xy 259.08 99.06)
		)
		(stroke
			(width 0)
			(type default)
		)
	)
	(wire
		(pts
			(xy 215.9 74.93) (xy 217.17 74.93)
		)
		(stroke
			(width 0)
			(type default)
		)
	)
	(wire
		(pts
			(xy 288.29 60.96) (xy 288.29 63.5)
		)
		(stroke
			(width 0)
			(type default)
		)
	)
	(wire
		(pts
			(xy 124.46 52.07) (xy 124.46 54.61)
		)
		(stroke
			(width 0)
			(type default)
		)
	)
	(wire
		(pts
			(xy 180.34 97.79) (xy 180.34 102.87)
		)
		(stroke
			(width 0)
			(type default)
		)
	)
	(wire
		(pts
			(xy 124.46 59.69) (xy 124.46 60.96)
		)
		(stroke
			(width 0)
			(type default)
		)
	)
	(wire
		(pts
			(xy 209.55 60.96) (xy 209.55 59.69)
		)
		(stroke
			(width 0)
			(type default)
		)
	)
	(wire
		(pts
			(xy 185.42 53.34) (xy 185.42 55.88)
		)
		(stroke
			(width 0)
			(type default)
		)
	)
	(wire
		(pts
			(xy 185.42 53.34) (xy 209.55 53.34)
		)
		(stroke
			(width 0)
			(type default)
		)
	)
	(wire
		(pts
			(xy 241.3 213.36) (xy 240.03 213.36)
		)
		(stroke
			(width 0)
			(type default)
		)
	)
	(wire
		(pts
			(xy 289.56 96.52) (xy 289.56 99.06)
		)
		(stroke
			(width 0)
			(type default)
		)
	)
	(wire
		(pts
			(xy 209.55 74.93) (xy 210.82 74.93)
		)
		(stroke
			(width 0)
			(type default)
		)
	)
	(wire
		(pts
			(xy 185.42 100.33) (xy 185.42 102.87)
		)
		(stroke
			(width 0)
			(type default)
		)
	)
	(polyline
		(pts
			(xy 134.62 132.08) (xy 167.64 132.08)
		)
		(stroke
			(width 0)
			(type default)
		)
	)
	(polyline
		(pts
			(xy 134.62 120.65) (xy 134.62 132.08)
		)
		(stroke
			(width 0)
			(type default)
		)
	)
	(wire
		(pts
			(xy 222.25 193.04) (xy 241.3 193.04)
		)
		(stroke
			(width 0)
			(type default)
		)
	)
	(polyline
		(pts
			(xy 241.3 100.33) (xy 241.3 109.22)
		)
		(stroke
			(width 0)
			(type default)
		)
	)
	(wire
		(pts
			(xy 217.17 74.93) (xy 222.25 74.93)
		)
		(stroke
			(width 0)
			(type default)
		)
	)
	(polyline
		(pts
			(xy 298.45 109.22) (xy 271.78 109.22)
		)
		(stroke
			(width 0)
			(type default)
		)
	)
	(wire
		(pts
			(xy 180.34 195.58) (xy 199.39 195.58)
		)
		(stroke
			(width 0)
			(type default)
		)
	)
	(wire
		(pts
			(xy 259.08 71.12) (xy 259.08 73.66)
		)
		(stroke
			(width 0)
			(type default)
		)
	)
	(wire
		(pts
			(xy 133.35 80.01) (xy 137.16 80.01)
		)
		(stroke
			(width 0)
			(type default)
		)
	)
	(wire
		(pts
			(xy 229.87 109.22) (xy 229.87 111.76)
		)
		(stroke
			(width 0)
			(type default)
		)
	)
	(wire
		(pts
			(xy 215.9 53.34) (xy 217.17 53.34)
		)
		(stroke
			(width 0)
			(type default)
		)
	)
	(wire
		(pts
			(xy 209.55 99.06) (xy 209.55 100.33)
		)
		(stroke
			(width 0)
			(type default)
		)
	)
	(wire
		(pts
			(xy 128.27 100.33) (xy 137.16 100.33)
		)
		(stroke
			(width 0)
			(type default)
		)
	)
	(wire
		(pts
			(xy 176.53 53.34) (xy 184.15 53.34)
		)
		(stroke
			(width 0)
			(type default)
		)
	)
	(wire
		(pts
			(xy 185.42 82.55) (xy 185.42 85.09)
		)
		(stroke
			(width 0)
			(type default)
		)
	)
	(polyline
		(pts
			(xy 269.24 81.28) (xy 241.3 81.28)
		)
		(stroke
			(width 0)
			(type default)
		)
	)
	(wire
		(pts
			(xy 222.25 110.49) (xy 222.25 111.76)
		)
		(stroke
			(width 0)
			(type default)
		)
	)
	(wire
		(pts
			(xy 288.29 71.12) (xy 288.29 73.66)
		)
		(stroke
			(width 0)
			(type default)
		)
	)
	(wire
		(pts
			(xy 209.55 60.96) (xy 198.12 60.96)
		)
		(stroke
			(width 0)
			(type default)
		)
	)
	(polyline
		(pts
			(xy 134.62 127) (xy 167.64 127)
		)
		(stroke
			(width 0)
			(type default)
		)
	)
	(wire
		(pts
			(xy 135.89 201.93) (xy 154.94 201.93)
		)
		(stroke
			(width 0)
			(type default)
		)
	)
	(wire
		(pts
			(xy 146.05 217.17) (xy 153.67 217.17)
		)
		(stroke
			(width 0)
			(type default)
		)
	)
	(wire
		(pts
			(xy 120.65 78.74) (xy 120.65 81.28)
		)
		(stroke
			(width 0)
			(type default)
		)
	)
	(wire
		(pts
			(xy 135.89 91.44) (xy 137.16 91.44)
		)
		(stroke
			(width 0)
			(type default)
		)
	)
	(wire
		(pts
			(xy 176.53 82.55) (xy 176.53 85.09)
		)
		(stroke
			(width 0)
			(type default)
		)
	)
	(wire
		(pts
			(xy 154.94 215.9) (xy 153.67 215.9)
		)
		(stroke
			(width 0)
			(type default)
		)
	)
	(polyline
		(pts
			(xy 134.62 137.16) (xy 167.64 137.16)
		)
		(stroke
			(width 0)
			(type default)
		)
	)
	(wire
		(pts
			(xy 248.92 88.9) (xy 259.08 88.9)
		)
		(stroke
			(width 0)
			(type default)
		)
	)
	(polyline
		(pts
			(xy 271.78 100.33) (xy 298.45 100.33)
		)
		(stroke
			(width 0)
			(type default)
		)
	)
	(wire
		(pts
			(xy 173.99 74.93) (xy 176.53 74.93)
		)
		(stroke
			(width 0)
			(type default)
		)
	)
	(wire
		(pts
			(xy 209.55 124.46) (xy 189.23 124.46)
		)
		(stroke
			(width 0)
			(type default)
		)
	)
	(polyline
		(pts
			(xy 162.56 124.46) (xy 162.56 137.16)
		)
		(stroke
			(width 0)
			(type default)
		)
	)
	(wire
		(pts
			(xy 259.08 78.74) (xy 259.08 81.28)
		)
		(stroke
			(width 0)
			(type default)
		)
	)
	(wire
		(pts
			(xy 241.3 209.55) (xy 232.41 209.55)
		)
		(stroke
			(width 0)
			(type default)
		)
	)
	(wire
		(pts
			(xy 176.53 63.5) (xy 185.42 63.5)
		)
		(stroke
			(width 0)
			(type default)
		)
	)
	(wire
		(pts
			(xy 220.98 91.44) (xy 220.98 92.71)
		)
		(stroke
			(width 0)
			(type default)
		)
	)
	(wire
		(pts
			(xy 240.03 199.39) (xy 241.3 199.39)
		)
		(stroke
			(width 0)
			(type default)
		)
	)
	(wire
		(pts
			(xy 185.42 111.76) (xy 209.55 111.76)
		)
		(stroke
			(width 0)
			(type default)
		)
	)
	(wire
		(pts
			(xy 209.55 53.34) (xy 210.82 53.34)
		)
		(stroke
			(width 0)
			(type default)
		)
	)
	(wire
		(pts
			(xy 176.53 85.09) (xy 185.42 85.09)
		)
		(stroke
			(width 0)
			(type default)
		)
	)
	(wire
		(pts
			(xy 184.15 52.07) (xy 184.15 53.34)
		)
		(stroke
			(width 0)
			(type default)
		)
	)
	(wire
		(pts
			(xy 209.55 118.11) (xy 209.55 124.46)
		)
		(stroke
			(width 0)
			(type default)
		)
	)
	(wire
		(pts
			(xy 120.65 72.39) (xy 120.65 73.66)
		)
		(stroke
			(width 0)
			(type default)
		)
	)
	(wire
		(pts
			(xy 165.1 95.25) (xy 168.91 95.25)
		)
		(stroke
			(width 0)
			(type default)
		)
	)
	(wire
		(pts
			(xy 185.42 102.87) (xy 185.42 104.14)
		)
		(stroke
			(width 0)
			(type default)
		)
	)
	(wire
		(pts
			(xy 114.3 60.96) (xy 114.3 62.23)
		)
		(stroke
			(width 0)
			(type default)
		)
	)
	(polyline
		(pts
			(xy 12.7 151.13) (xy 407.67 151.13)
		)
		(stroke
			(width 0)
			(type default)
		)
	)
	(wire
		(pts
			(xy 283.21 71.12) (xy 288.29 71.12)
		)
		(stroke
			(width 0)
			(type default)
		)
	)
	(wire
		(pts
			(xy 240.03 217.17) (xy 240.03 218.44)
		)
		(stroke
			(width 0)
			(type default)
		)
	)
	(wire
		(pts
			(xy 209.55 81.28) (xy 209.55 82.55)
		)
		(stroke
			(width 0)
			(type default)
		)
	)
	(polyline
		(pts
			(xy 241.3 72.39) (xy 269.24 72.39)
		)
		(stroke
			(width 0)
			(type default)
		)
	)
	(wire
		(pts
			(xy 289.56 88.9) (xy 289.56 91.44)
		)
		(stroke
			(width 0)
			(type default)
		)
	)
	(polyline
		(pts
			(xy 267.97 100.33) (xy 267.97 109.22)
		)
		(stroke
			(width 0)
			(type default)
		)
	)
	(polyline
		(pts
			(xy 134.62 132.08) (xy 134.62 137.16)
		)
		(stroke
			(width 0)
			(type default)
		)
	)
	(polyline
		(pts
			(xy 167.64 124.46) (xy 147.32 124.46)
		)
		(stroke
			(width 0)
			(type default)
		)
	)
	(wire
		(pts
			(xy 176.53 111.76) (xy 185.42 111.76)
		)
		(stroke
			(width 0)
			(type default)
		)
	)
	(polyline
		(pts
			(xy 167.64 120.65) (xy 134.62 120.65)
		)
		(stroke
			(width 0)
			(type default)
		)
	)
	(wire
		(pts
			(xy 153.67 217.17) (xy 153.67 218.44)
		)
		(stroke
			(width 0)
			(type default)
		)
	)
	(wire
		(pts
			(xy 259.08 68.58) (xy 259.08 71.12)
		)
		(stroke
			(width 0)
			(type default)
		)
	)
	(wire
		(pts
			(xy 180.34 199.39) (xy 199.39 199.39)
		)
		(stroke
			(width 0)
			(type default)
		)
	)
	(wire
		(pts
			(xy 288.29 68.58) (xy 288.29 71.12)
		)
		(stroke
			(width 0)
			(type default)
		)
	)
	(wire
		(pts
			(xy 185.42 111.76) (xy 185.42 114.3)
		)
		(stroke
			(width 0)
			(type default)
		)
	)
	(wire
		(pts
			(xy 222.25 53.34) (xy 229.87 53.34)
		)
		(stroke
			(width 0)
			(type default)
		)
	)
	(wire
		(pts
			(xy 185.42 74.93) (xy 185.42 77.47)
		)
		(stroke
			(width 0)
			(type default)
		)
	)
	(wire
		(pts
			(xy 173.99 82.55) (xy 173.99 74.93)
		)
		(stroke
			(width 0)
			(type default)
		)
	)
	(wire
		(pts
			(xy 165.1 77.47) (xy 171.45 77.47)
		)
		(stroke
			(width 0)
			(type default)
		)
	)
	(wire
		(pts
			(xy 165.1 92.71) (xy 185.42 92.71)
		)
		(stroke
			(width 0)
			(type default)
		)
	)
	(wire
		(pts
			(xy 165.1 97.79) (xy 180.34 97.79)
		)
		(stroke
			(width 0)
			(type default)
		)
	)
	(wire
		(pts
			(xy 146.05 209.55) (xy 146.05 210.82)
		)
		(stroke
			(width 0)
			(type default)
		)
	)
	(wire
		(pts
			(xy 185.42 92.71) (xy 185.42 95.25)
		)
		(stroke
			(width 0)
			(type default)
		)
	)
	(wire
		(pts
			(xy 124.46 60.96) (xy 114.3 60.96)
		)
		(stroke
			(width 0)
			(type default)
		)
	)
	(label "MGTAVCC_local"
		(at 279.4 60.96 0)
		(effects
			(font
				(size 1.27 1.27)
			)
			(justify left bottom)
		)
	)
	(label "MGTAVTT_local"
		(at 248.92 88.9 0)
		(effects
			(font
				(size 1.27 1.27)
			)
			(justify left bottom)
		)
	)
	(label "1V8_SEN_+"
		(at 199.39 193.04 180)
		(effects
			(font
				(size 1.27 1.27)
			)
			(justify right bottom)
		)
	)
	(label "1V8_SEN_-"
		(at 199.39 195.58 180)
		(effects
			(font
				(size 1.27 1.27)
			)
			(justify right bottom)
		)
	)
	(label "1V8_SEN_-"
		(at 229.87 60.96 180)
		(effects
			(font
				(size 1.27 1.27)
			)
			(justify right bottom)
		)
	)
	(label "1V8_local"
		(at 243.84 60.96 0)
		(effects
			(font
				(size 1.27 1.27)
			)
			(justify left bottom)
		)
	)
	(label "FB1"
		(at 254 71.12 0)
		(effects
			(font
				(size 1.27 1.27)
			)
			(justify left bottom)
		)
	)
	(label "MGTAVTT_SEN_-"
		(at 233.68 82.55 180)
		(effects
			(font
				(size 1.27 1.27)
			)
			(justify right bottom)
		)
	)
	(label "MGTAVCCAUX_SEN_-"
		(at 238.76 124.46 180)
		(effects
			(font
				(size 1.27 1.27)
			)
			(justify right bottom)
		)
	)
	(label "1V8_SEN_+"
		(at 198.12 60.96 0)
		(effects
			(font
				(size 1.27 1.27)
			)
			(justify left bottom)
		)
	)
	(label "FB3"
		(at 283.21 71.12 0)
		(effects
			(font
				(size 1.27 1.27)
			)
			(justify left bottom)
		)
	)
	(label "MGTAVTT_SEN_-"
		(at 285.75 201.93 180)
		(effects
			(font
				(size 1.27 1.27)
			)
			(justify right bottom)
		)
	)
	(label "MGTAVTT_SEN_+"
		(at 285.75 199.39 180)
		(effects
			(font
				(size 1.27 1.27)
			)
			(justify right bottom)
		)
	)
	(label "FB2"
		(at 168.91 87.63 180)
		(effects
			(font
				(size 1.27 1.27)
			)
			(justify right bottom)
		)
	)
	(label "MGTAVTT_local"
		(at 185.42 74.93 0)
		(effects
			(font
				(size 1.27 1.27)
			)
			(justify left bottom)
		)
	)
	(label "MGTAVCC_SEN_-"
		(at 285.75 195.58 180)
		(effects
			(font
				(size 1.27 1.27)
			)
			(justify right bottom)
		)
	)
	(label "MGTAVCCAUX_SEN_+"
		(at 189.23 124.46 0)
		(effects
			(font
				(size 1.27 1.27)
			)
			(justify left bottom)
		)
	)
	(label "FB4"
		(at 168.91 105.41 180)
		(effects
			(font
				(size 1.27 1.27)
			)
			(justify right bottom)
		)
	)
	(label "FB1"
		(at 168.91 74.93 180)
		(effects
			(font
				(size 1.27 1.27)
			)
			(justify right bottom)
		)
	)
	(label "MGTAVCCAUX_SEN_+"
		(at 199.39 199.39 180)
		(effects
			(font
				(size 1.27 1.27)
			)
			(justify right bottom)
		)
	)
	(label "QDCDC1_VCC"
		(at 123.19 72.39 0)
		(effects
			(font
				(size 1.27 1.27)
			)
			(justify left bottom)
		)
	)
	(label "MGTAVCC_SEN_+"
		(at 193.04 100.33 0)
		(effects
			(font
				(size 1.27 1.27)
			)
			(justify left bottom)
		)
	)
	(label "FB4"
		(at 284.48 99.06 0)
		(effects
			(font
				(size 1.27 1.27)
			)
			(justify left bottom)
		)
	)
	(label "MGTAVCC_SEN_+"
		(at 285.75 193.04 180)
		(effects
			(font
				(size 1.27 1.27)
			)
			(justify right bottom)
		)
	)
	(label "MGTAVCCAUX_local"
		(at 279.4 88.9 0)
		(effects
			(font
				(size 1.27 1.27)
			)
			(justify left bottom)
		)
	)
	(label "MGTAVCCAUX_SEN_-"
		(at 199.39 201.93 180)
		(effects
			(font
				(size 1.27 1.27)
			)
			(justify right bottom)
		)
	)
	(label "FB3"
		(at 168.91 95.25 180)
		(effects
			(font
				(size 1.27 1.27)
			)
			(justify right bottom)
		)
	)
	(label "FB2"
		(at 252.73 99.06 0)
		(effects
			(font
				(size 1.27 1.27)
			)
			(justify left bottom)
		)
	)
	(label "MGTAVCC_local"
		(at 185.42 92.71 0)
		(effects
			(font
				(size 1.27 1.27)
			)
			(justify left bottom)
		)
	)
	(label "1V8_local"
		(at 185.42 53.34 0)
		(effects
			(font
				(size 1.27 1.27)
			)
			(justify left bottom)
		)
	)
	(label "MGTAVCCAUX_local"
		(at 185.42 111.76 0)
		(effects
			(font
				(size 1.27 1.27)
			)
			(justify left bottom)
		)
	)
	(label "MGTAVTT_SEN_+"
		(at 193.04 82.55 0)
		(effects
			(font
				(size 1.27 1.27)
			)
			(justify left bottom)
		)
	)
	(label "MGTAVCC_SEN_-"
		(at 233.68 100.33 180)
		(effects
			(font
				(size 1.27 1.27)
			)
			(justify right bottom)
		)
	)
	(global_label "PG2"
		(shape input)
		(at 128.27 100.33 180)
		(fields_autoplaced yes)
		(effects
			(font
				(size 1.27 1.27)
			)
			(justify right)
		)
		(property "Intersheetrefs" "${INTERSHEET_REFS}"
			(at 122.1895 100.33 0)
			(effects
				(font
					(size 1.27 1.27)
				)
				(justify right)
			)
		)
	)
	(hierarchical_label "PWR.SDA"
		(shape input)
		(at 135.89 88.9 180)
		(effects
			(font
				(size 1.27 1.27)
			)
			(justify right)
		)
	)
	(hierarchical_label "EN2"
		(shape input)
		(at 133.35 80.01 180)
		(effects
			(font
				(size 1.27 1.27)
			)
			(justify right)
		)
	)
	(hierarchical_label "PWR.SDA"
		(shape input)
		(at 153.67 199.39 180)
		(effects
			(font
				(size 1.27 1.27)
			)
			(justify right)
		)
	)
	(hierarchical_label "PWR.SCL"
		(shape input)
		(at 153.67 196.85 180)
		(effects
			(font
				(size 1.27 1.27)
			)
			(justify right)
		)
	)
	(hierarchical_label "PWR.SCL"
		(shape input)
		(at 135.89 91.44 180)
		(effects
			(font
				(size 1.27 1.27)
			)
			(justify right)
		)
	)
	(hierarchical_label "PWR.SCL"
		(shape input)
		(at 240.03 196.85 180)
		(effects
			(font
				(size 1.27 1.27)
			)
			(justify right)
		)
	)
	(hierarchical_label "PWR.SDA"
		(shape input)
		(at 240.03 199.39 180)
		(effects
			(font
				(size 1.27 1.27)
			)
			(justify right)
		)
	)
	(symbol
		(lib_id "antmicroResistors0402:R_47k_0402")
		(at 135.89 200.66 270)
		(mirror x)
		(unit 1)
		(exclude_from_sim no)
		(in_bom yes)
		(on_board yes)
		(dnp no)
		(fields_autoplaced yes)
		(property "Reference" "R143"
			(at 138.43 196.85 90)
			(effects
				(font
					(size 1.27 1.27)
				)
				(justify left)
			)
		)
		(property "Value" "R_47k_0402"
			(at 123.19 180.34 0)
			(effects
				(font
					(size 1.27 1.27)
					(thickness 0.15)
				)
				(justify left bottom)
				(hide yes)
			)
		)
		(property "Footprint" "antmicro-footprints:R_0402_1005Metric"
			(at 120.65 180.34 0)
			(effects
				(font
					(size 1.27 1.27)
					(thickness 0.15)
				)
				(justify left bottom)
				(hide yes)
			)
		)
		(property "Datasheet" "https://www.bourns.com/docs/product-datasheets/cr.pdf"
			(at 118.11 180.34 0)
			(effects
				(font
					(size 1.27 1.27)
					(thickness 0.15)
				)
				(justify left bottom)
				(hide yes)
			)
		)
		(property "Description" ""
			(at 135.89 200.66 0)
			(effects
				(font
					(size 1.27 1.27)
				)
				(hide yes)
			)
		)
		(property "Manufacturer" "Bourns"
			(at 113.03 180.34 0)
			(effects
				(font
					(size 1.27 1.27)
					(thickness 0.15)
				)
				(justify left bottom)
				(hide yes)
			)
		)
		(property "MPN" "CR0402-FX-4702GLF"
			(at 115.57 180.34 0)
			(effects
				(font
					(size 1.27 1.27)
					(thickness 0.15)
				)
				(justify left bottom)
				(hide yes)
			)
		)
		(property "Val" "47k"
			(at 138.43 199.39 90)
			(effects
				(font
					(size 1.27 1.27)
					(thickness 0.15)
				)
				(justify left)
			)
		)
		(property "License" "Apache-2.0"
			(at 110.49 180.34 0)
			(effects
				(font
					(size 1.27 1.27)
					(thickness 0.15)
				)
				(justify left bottom)
				(hide yes)
			)
		)
		(property "Author" "Antmicro"
			(at 107.95 180.34 0)
			(effects
				(font
					(size 1.27 1.27)
					(thickness 0.15)
				)
				(justify left bottom)
				(hide yes)
			)
		)
		(property "Tolerance" "1%"
			(at 125.73 180.34 0)
			(effects
				(font
					(size 1.27 1.27)
				)
				(justify left bottom)
				(hide yes)
			)
		)
		(pin "1"
		)
		(pin "2"
		)
		(instances
			(project "data-center-rdimm-ddr5-tester"
				(path ""
					(reference "R143")
					(unit 1)
				)
			)
		)
	)
	(symbol
		(lib_id "antmicroResistors0402:R_0R_0402")
		(at 288.29 78.74 90)
		(unit 1)
		(exclude_from_sim no)
		(in_bom no)
		(on_board yes)
		(dnp yes)
		(property "Reference" "R164"
			(at 290.83 74.93 90)
			(effects
				(font
					(size 1.27 1.27)
				)
				(justify right)
			)
		)
		(property "Value" "R_0R_0402"
			(at 300.99 58.42 0)
			(effects
				(font
					(size 1.27 1.27)
					(thickness 0.15)
				)
				(justify left bottom)
				(hide yes)
			)
		)
		(property "Footprint" "antmicro-footprints:R_0402_1005Metric"
			(at 303.53 58.42 0)
			(effects
				(font
					(size 1.27 1.27)
					(thickness 0.15)
				)
				(justify left bottom)
				(hide yes)
			)
		)
		(property "Datasheet" "https://industrial.panasonic.com/cdbs/www-data/pdf/RDA0000/AOA0000C301.pdf"
			(at 306.07 58.42 0)
			(effects
				(font
					(size 1.27 1.27)
					(thickness 0.15)
				)
				(justify left bottom)
				(hide yes)
			)
		)
		(property "Description" ""
			(at 288.29 78.74 0)
			(effects
				(font
					(size 1.27 1.27)
				)
				(hide yes)
			)
		)
		(property "Manufacturer" "Panasonic"
			(at 311.15 58.42 0)
			(effects
				(font
					(size 1.27 1.27)
					(thickness 0.15)
				)
				(justify left bottom)
				(hide yes)
			)
		)
		(property "MPN" "ERJ2GE0R00X"
			(at 308.61 58.42 0)
			(effects
				(font
					(size 1.27 1.27)
					(thickness 0.15)
				)
				(justify left bottom)
				(hide yes)
			)
		)
		(property "Val" "0R"
			(at 290.83 77.47 90)
			(effects
				(font
					(size 1.27 1.27)
					(thickness 0.15)
				)
				(justify right)
			)
		)
		(property "License" "Apache-2.0"
			(at 313.69 58.42 0)
			(effects
				(font
					(size 1.27 1.27)
					(thickness 0.15)
				)
				(justify left bottom)
				(hide yes)
			)
		)
		(property "Author" "Antmicro"
			(at 316.23 58.42 0)
			(effects
				(font
					(size 1.27 1.27)
					(thickness 0.15)
				)
				(justify left bottom)
				(hide yes)
			)
		)
		(property "Tolerance" "~"
			(at 298.45 58.42 0)
			(effects
				(font
					(size 1.27 1.27)
				)
				(justify left bottom)
				(hide yes)
			)
		)
		(property "Current" "1A"
			(at 290.83 80.0099 90)
			(effects
				(font
					(size 1.27 1.27)
					(thickness 0.15)
				)
				(justify right)
				(hide yes)
			)
		)
		(pin "1"
		)
		(pin "2"
		)
		(instances
			(project "data-center-rdimm-ddr5-tester"
				(path ""
					(reference "R164")
					(unit 1)
				)
			)
		)
	)
	(symbol
		(lib_id "antmicropower:PWR_FLAG")
		(at 222.25 73.66 0)
		(unit 1)
		(exclude_from_sim no)
		(in_bom yes)
		(on_board yes)
		(dnp no)
		(fields_autoplaced yes)
		(property "Reference" "#FLG010"
			(at 222.25 71.755 0)
			(effects
				(font
					(size 1.27 1.27)
				)
				(hide yes)
			)
		)
		(property "Value" "PWR_FLAG"
			(at 222.25 70.0842 0)
			(effects
				(font
					(size 1.27 1.27)
				)
			)
		)
		(property "Footprint" ""
			(at 222.25 73.66 0)
			(effects
				(font
					(size 1.27 1.27)
				)
				(hide yes)
			)
		)
		(property "Datasheet" ""
			(at 222.25 73.66 0)
			(effects
				(font
					(size 1.27 1.27)
				)
				(hide yes)
			)
		)
		(property "Description" ""
			(at 222.25 73.66 0)
			(effects
				(font
					(size 1.27 1.27)
				)
				(hide yes)
			)
		)
		(pin "1"
		)
		(instances
			(project "data-center-rdimm-ddr5-tester"
				(path ""
					(reference "#FLG010")
					(unit 1)
				)
			)
		)
	)
	(symbol
		(lib_id "antmicroPowerMeasurement:PAC1720-1-AIA-TR")
		(at 154.94 193.04 0)
		(unit 1)
		(exclude_from_sim no)
		(in_bom yes)
		(on_board yes)
		(dnp no)
		(fields_autoplaced yes)
		(property "Reference" "U3"
			(at 167.64 185.42 0)
			(effects
				(font
					(size 1.27 1.27)
					(thickness 0.15)
				)
			)
		)
		(property "Value" "PAC1720-1"
			(at 193.04 200.66 0)
			(effects
				(font
					(size 1.27 1.27)
					(thickness 0.15)
				)
				(justify left bottom)
				(hide yes)
			)
		)
		(property "Footprint" "antmicro-footprints:DFN-10-1EP_3x3mm"
			(at 193.04 203.2 0)
			(effects
				(font
					(size 1.27 1.27)
					(thickness 0.15)
				)
				(justify left bottom)
				(hide yes)
			)
		)
		(property "Datasheet" "https://ww1.microchip.com/downloads/aemDocuments/documents/MSLD/ProductDocuments/DataSheets/PAC1710-PAC1720-Data-Sheet-DS20005386.pdf"
			(at 193.04 205.74 0)
			(effects
				(font
					(size 1.27 1.27)
					(thickness 0.15)
				)
				(justify left bottom)
				(hide yes)
			)
		)
		(property "Description" ""
			(at 154.94 193.04 0)
			(effects
				(font
					(size 1.27 1.27)
				)
				(hide yes)
			)
		)
		(property "MPN" "PAC1720-1-AIA-TR"
			(at 167.64 187.96 0)
			(effects
				(font
					(size 1.27 1.27)
					(thickness 0.15)
				)
			)
		)
		(property "Manufacturer" "Microchip Technology"
			(at 193.04 208.28 0)
			(effects
				(font
					(size 1.27 1.27)
					(thickness 0.15)
				)
				(justify left bottom)
				(hide yes)
			)
		)
		(property "Author" "Antmicro"
			(at 193.04 210.82 0)
			(effects
				(font
					(size 1.27 1.27)
					(thickness 0.15)
				)
				(justify left bottom)
				(hide yes)
			)
		)
		(property "License" "Apache-2.0"
			(at 193.04 213.36 0)
			(effects
				(font
					(size 1.27 1.27)
					(thickness 0.15)
				)
				(justify left bottom)
				(hide yes)
			)
		)
		(pin "7"
		)
		(pin "3"
		)
		(pin "9"
		)
		(pin "10"
		)
		(pin "8"
		)
		(pin "2"
		)
		(pin "4"
		)
		(pin "11"
		)
		(pin "1"
		)
		(pin "5"
		)
		(pin "6"
		)
		(instances
			(project "data-center-rdimm-ddr5-tester"
				(path ""
					(reference "U3")
					(unit 1)
				)
			)
		)
	)
	(symbol
		(lib_id "antmicroPowerMeasurement:PAC1720-1-AIA-TR")
		(at 241.3 193.04 0)
		(unit 1)
		(exclude_from_sim no)
		(in_bom yes)
		(on_board yes)
		(dnp no)
		(fields_autoplaced yes)
		(property "Reference" "U25"
			(at 254 185.42 0)
			(effects
				(font
					(size 1.27 1.27)
					(thickness 0.15)
				)
			)
		)
		(property "Value" "PAC1720-1"
			(at 279.4 200.66 0)
			(effects
				(font
					(size 1.27 1.27)
					(thickness 0.15)
				)
				(justify left bottom)
				(hide yes)
			)
		)
		(property "Footprint" "antmicro-footprints:DFN-10-1EP_3x3mm"
			(at 279.4 203.2 0)
			(effects
				(font
					(size 1.27 1.27)
					(thickness 0.15)
				)
				(justify left bottom)
				(hide yes)
			)
		)
		(property "Datasheet" "https://ww1.microchip.com/downloads/aemDocuments/documents/MSLD/ProductDocuments/DataSheets/PAC1710-PAC1720-Data-Sheet-DS20005386.pdf"
			(at 279.4 205.74 0)
			(effects
				(font
					(size 1.27 1.27)
					(thickness 0.15)
				)
				(justify left bottom)
				(hide yes)
			)
		)
		(property "Description" ""
			(at 241.3 193.04 0)
			(effects
				(font
					(size 1.27 1.27)
				)
				(hide yes)
			)
		)
		(property "MPN" "PAC1720-1-AIA-TR"
			(at 254 187.96 0)
			(effects
				(font
					(size 1.27 1.27)
					(thickness 0.15)
				)
			)
		)
		(property "Manufacturer" "Microchip Technology"
			(at 279.4 208.28 0)
			(effects
				(font
					(size 1.27 1.27)
					(thickness 0.15)
				)
				(justify left bottom)
				(hide yes)
			)
		)
		(property "Author" "Antmicro"
			(at 279.4 210.82 0)
			(effects
				(font
					(size 1.27 1.27)
					(thickness 0.15)
				)
				(justify left bottom)
				(hide yes)
			)
		)
		(property "License" "Apache-2.0"
			(at 279.4 213.36 0)
			(effects
				(font
					(size 1.27 1.27)
					(thickness 0.15)
				)
				(justify left bottom)
				(hide yes)
			)
		)
		(pin "7"
		)
		(pin "3"
		)
		(pin "9"
		)
		(pin "10"
		)
		(pin "8"
		)
		(pin "2"
		)
		(pin "4"
		)
		(pin "11"
		)
		(pin "1"
		)
		(pin "5"
		)
		(pin "6"
		)
		(instances
			(project "data-center-rdimm-ddr5-tester"
				(path ""
					(reference "U25")
					(unit 1)
				)
			)
		)
	)
	(symbol
		(lib_id "antmicropower:+1V2_MGTAVTT")
		(at 229.87 71.12 0)
		(unit 1)
		(exclude_from_sim no)
		(in_bom yes)
		(on_board yes)
		(dnp no)
		(fields_autoplaced yes)
		(property "Reference" "#PWR0321"
			(at 229.87 74.93 0)
			(effects
				(font
					(size 1.27 1.27)
				)
				(hide yes)
			)
		)
		(property "Value" "+1V2_MGTAVTT"
			(at 229.87 67.31 0)
			(effects
				(font
					(size 1.27 1.27)
				)
			)
		)
		(property "Footprint" ""
			(at 229.87 71.12 0)
			(effects
				(font
					(size 1.27 1.27)
				)
				(hide yes)
			)
		)
		(property "Datasheet" ""
			(at 229.87 71.12 0)
			(effects
				(font
					(size 1.27 1.27)
				)
				(hide yes)
			)
		)
		(property "Description" ""
			(at 229.87 71.12 0)
			(effects
				(font
					(size 1.27 1.27)
				)
				(hide yes)
			)
		)
		(pin "1"
		)
		(instances
			(project "data-center-rdimm-ddr5-tester"
				(path ""
					(reference "#PWR0321")
					(unit 1)
				)
			)
		)
	)
	(symbol
		(lib_id "antmicropower:+0V9_MGTAVCC")
		(at 229.87 90.17 0)
		(unit 1)
		(exclude_from_sim no)
		(in_bom yes)
		(on_board yes)
		(dnp no)
		(property "Reference" "#PWR058"
			(at 229.87 93.98 0)
			(effects
				(font
					(size 1.27 1.27)
				)
				(hide yes)
			)
		)
		(property "Value" "+0V9_MGTAVCC"
			(at 229.87 85.725 0)
			(effects
				(font
					(size 1.27 1.27)
				)
			)
		)
		(property "Footprint" ""
			(at 229.87 90.17 0)
			(effects
				(font
					(size 1.27 1.27)
				)
				(hide yes)
			)
		)
		(property "Datasheet" ""
			(at 229.87 90.17 0)
			(effects
				(font
					(size 1.27 1.27)
				)
				(hide yes)
			)
		)
		(property "Description" ""
			(at 229.87 90.17 0)
			(effects
				(font
					(size 1.27 1.27)
				)
				(hide yes)
			)
		)
		(pin "1"
		)
		(instances
			(project "data-center-rdimm-ddr5-tester"
				(path ""
					(reference "#PWR058")
					(unit 1)
				)
			)
		)
	)
	(symbol
		(lib_id "antmicropower:GND")
		(at 185.42 86.36 0)
		(unit 1)
		(exclude_from_sim no)
		(in_bom yes)
		(on_board yes)
		(dnp no)
		(fields_autoplaced yes)
		(property "Reference" "#PWR0304"
			(at 185.42 92.71 0)
			(effects
				(font
					(size 1.27 1.27)
				)
				(hide yes)
			)
		)
		(property "Value" "GND"
			(at 183.515 90.805 0)
			(effects
				(font
					(size 1.27 1.27)
					(thickness 0.15)
				)
				(justify left bottom)
			)
		)
		(property "Footprint" ""
			(at 194.31 93.98 0)
			(effects
				(font
					(size 1.27 1.27)
					(thickness 0.15)
				)
				(justify left bottom)
				(hide yes)
			)
		)
		(property "Datasheet" ""
			(at 194.31 99.06 0)
			(effects
				(font
					(size 1.27 1.27)
					(thickness 0.15)
				)
				(justify left bottom)
				(hide yes)
			)
		)
		(property "Description" ""
			(at 185.42 86.36 0)
			(effects
				(font
					(size 1.27 1.27)
				)
				(hide yes)
			)
		)
		(property "Author" "Antmicro"
			(at 194.31 91.44 0)
			(effects
				(font
					(size 1.27 1.27)
					(thickness 0.15)
				)
				(justify left bottom)
				(hide yes)
			)
		)
		(property "License" "Apache-2.0"
			(at 194.31 93.98 0)
			(effects
				(font
					(size 1.27 1.27)
					(thickness 0.15)
				)
				(justify left bottom)
				(hide yes)
			)
		)
		(pin "1"
		)
		(instances
			(project "data-center-rdimm-ddr5-tester"
				(path ""
					(reference "#PWR0304")
					(unit 1)
				)
			)
		)
	)
	(symbol
		(lib_id "antmicropower:VDC")
		(at 114.3 50.8 0)
		(unit 1)
		(exclude_from_sim no)
		(in_bom yes)
		(on_board yes)
		(dnp no)
		(fields_autoplaced yes)
		(property "Reference" "#PWR0278"
			(at 114.3 53.34 0)
			(effects
				(font
					(size 1.27 1.27)
				)
				(hide yes)
			)
		)
		(property "Value" "VDC"
			(at 114.3 45.72 0)
			(effects
				(font
					(size 1.27 1.27)
				)
			)
		)
		(property "Footprint" ""
			(at 114.3 50.8 0)
			(effects
				(font
					(size 1.27 1.27)
				)
				(hide yes)
			)
		)
		(property "Datasheet" ""
			(at 114.3 50.8 0)
			(effects
				(font
					(size 1.27 1.27)
				)
				(hide yes)
			)
		)
		(property "Description" ""
			(at 114.3 50.8 0)
			(effects
				(font
					(size 1.27 1.27)
				)
				(hide yes)
			)
		)
		(pin "1"
		)
		(instances
			(project "data-center-rdimm-ddr5-tester"
				(path ""
					(reference "#PWR0278")
					(unit 1)
				)
			)
		)
	)
	(symbol
		(lib_id "antmicropower:GND")
		(at 185.42 120.65 0)
		(unit 1)
		(exclude_from_sim no)
		(in_bom yes)
		(on_board yes)
		(dnp no)
		(fields_autoplaced yes)
		(property "Reference" "#PWR0306"
			(at 185.42 127 0)
			(effects
				(font
					(size 1.27 1.27)
				)
				(hide yes)
			)
		)
		(property "Value" "GND"
			(at 183.515 125.095 0)
			(effects
				(font
					(size 1.27 1.27)
					(thickness 0.15)
				)
				(justify left bottom)
			)
		)
		(property "Footprint" ""
			(at 194.31 128.27 0)
			(effects
				(font
					(size 1.27 1.27)
					(thickness 0.15)
				)
				(justify left bottom)
				(hide yes)
			)
		)
		(property "Datasheet" ""
			(at 194.31 133.35 0)
			(effects
				(font
					(size 1.27 1.27)
					(thickness 0.15)
				)
				(justify left bottom)
				(hide yes)
			)
		)
		(property "Description" ""
			(at 185.42 120.65 0)
			(effects
				(font
					(size 1.27 1.27)
				)
				(hide yes)
			)
		)
		(property "Author" "Antmicro"
			(at 194.31 125.73 0)
			(effects
				(font
					(size 1.27 1.27)
					(thickness 0.15)
				)
				(justify left bottom)
				(hide yes)
			)
		)
		(property "License" "Apache-2.0"
			(at 194.31 128.27 0)
			(effects
				(font
					(size 1.27 1.27)
					(thickness 0.15)
				)
				(justify left bottom)
				(hide yes)
			)
		)
		(pin "1"
		)
		(instances
			(project "data-center-rdimm-ddr5-tester"
				(path ""
					(reference "#PWR0306")
					(unit 1)
				)
			)
		)
	)
	(symbol
		(lib_id "antmicroTestPoints:TP_1mm_SMD")
		(at 229.87 53.34 0)
		(unit 1)
		(exclude_from_sim no)
		(in_bom no)
		(on_board yes)
		(dnp no)
		(fields_autoplaced yes)
		(property "Reference" "TP8"
			(at 234.442 53.7738 0)
			(effects
				(font
					(size 1.27 1.27)
				)
				(justify left)
			)
		)
		(property "Value" "TP_1mm_SMD"
			(at 245.11 60.96 0)
			(effects
				(font
					(size 1.27 1.27)
					(thickness 0.15)
				)
				(justify left bottom)
				(hide yes)
			)
		)
		(property "Footprint" "antmicro-footprints:TP_SMD_1mm"
			(at 245.11 63.5 0)
			(effects
				(font
					(size 1.27 1.27)
					(thickness 0.15)
				)
				(justify left bottom)
				(hide yes)
			)
		)
		(property "Datasheet" ""
			(at 245.11 66.04 0)
			(effects
				(font
					(size 1.27 1.27)
					(thickness 0.15)
				)
				(justify left bottom)
				(hide yes)
			)
		)
		(property "Description" ""
			(at 229.87 53.34 0)
			(effects
				(font
					(size 1.27 1.27)
				)
				(hide yes)
			)
		)
		(property "MPN" ""
			(at 229.87 53.34 0)
			(effects
				(font
					(size 1.27 1.27)
				)
				(hide yes)
			)
		)
		(property "Manufacturer" ""
			(at 229.87 53.34 0)
			(effects
				(font
					(size 1.27 1.27)
				)
				(hide yes)
			)
		)
		(property "Author" "Antmicro"
			(at 245.11 68.58 0)
			(effects
				(font
					(size 1.27 1.27)
					(thickness 0.15)
				)
				(justify left bottom)
				(hide yes)
			)
		)
		(property "License" "Apache-2.0"
			(at 245.11 71.12 0)
			(effects
				(font
					(size 1.27 1.27)
					(thickness 0.15)
				)
				(justify left bottom)
				(hide yes)
			)
		)
		(pin "1"
		)
		(instances
			(project "data-center-rdimm-ddr5-tester"
				(path ""
					(reference "TP8")
					(unit 1)
				)
			)
		)
	)
	(symbol
		(lib_id "antmicroCapacitors0603:C_22u_0603")
		(at 185.42 100.33 90)
		(unit 1)
		(exclude_from_sim no)
		(in_bom yes)
		(on_board yes)
		(dnp no)
		(fields_autoplaced yes)
		(property "Reference" "C189"
			(at 187.7441 96.953 90)
			(effects
				(font
					(size 1.27 1.27)
				)
				(justify right)
			)
		)
		(property "Value" "C_22u_0603"
			(at 195.58 80.01 0)
			(effects
				(font
					(size 1.27 1.27)
					(thickness 0.15)
				)
				(justify left bottom)
				(hide yes)
			)
		)
		(property "Footprint" "antmicro-footprints:C_0603_1608Metric"
			(at 198.12 80.01 0)
			(effects
				(font
					(size 1.27 1.27)
					(thickness 0.15)
				)
				(justify left bottom)
				(hide yes)
			)
		)
		(property "Datasheet" "https://www.murata.com/products/productdetail?partno=GRM188R60J226MEA0%23"
			(at 200.66 80.01 0)
			(effects
				(font
					(size 1.27 1.27)
					(thickness 0.15)
				)
				(justify left bottom)
				(hide yes)
			)
		)
		(property "Description" ""
			(at 185.42 100.33 0)
			(effects
				(font
					(size 1.27 1.27)
				)
				(hide yes)
			)
		)
		(property "Manufacturer" "Murata"
			(at 205.74 80.01 0)
			(effects
				(font
					(size 1.27 1.27)
					(thickness 0.15)
				)
				(justify left bottom)
				(hide yes)
			)
		)
		(property "MPN" "GRM188R60J226MEA0D"
			(at 203.2 80.01 0)
			(effects
				(font
					(size 1.27 1.27)
					(thickness 0.15)
				)
				(justify left bottom)
				(hide yes)
			)
		)
		(property "Val" "22u"
			(at 187.7441 99.4833 90)
			(effects
				(font
					(size 1.27 1.27)
					(thickness 0.15)
				)
				(justify right)
			)
		)
		(property "License" "Apache-2.0"
			(at 208.28 80.01 0)
			(effects
				(font
					(size 1.27 1.27)
					(thickness 0.15)
				)
				(justify left bottom)
				(hide yes)
			)
		)
		(property "Author" "Antmicro"
			(at 210.82 80.01 0)
			(effects
				(font
					(size 1.27 1.27)
					(thickness 0.15)
				)
				(justify left bottom)
				(hide yes)
			)
		)
		(property "Voltage" ""
			(at 213.36 80.01 0)
			(effects
				(font
					(size 1.27 1.27)
				)
				(justify left bottom)
				(hide yes)
			)
		)
		(property "Dielectric" ""
			(at 215.9 80.01 0)
			(effects
				(font
					(size 1.27 1.27)
				)
				(justify left bottom)
				(hide yes)
			)
		)
		(pin "1"
		)
		(pin "2"
		)
		(instances
			(project "data-center-rdimm-ddr5-tester"
				(path ""
					(reference "C189")
					(unit 1)
				)
			)
		)
	)
	(symbol
		(lib_id "antmicropower:PWR_FLAG")
		(at 222.25 110.49 0)
		(unit 1)
		(exclude_from_sim no)
		(in_bom yes)
		(on_board yes)
		(dnp no)
		(fields_autoplaced yes)
		(property "Reference" "#FLG011"
			(at 222.25 108.585 0)
			(effects
				(font
					(size 1.27 1.27)
				)
				(hide yes)
			)
		)
		(property "Value" "PWR_FLAG"
			(at 222.25 106.9142 0)
			(effects
				(font
					(size 1.27 1.27)
				)
			)
		)
		(property "Footprint" ""
			(at 222.25 110.49 0)
			(effects
				(font
					(size 1.27 1.27)
				)
				(hide yes)
			)
		)
		(property "Datasheet" ""
			(at 222.25 110.49 0)
			(effects
				(font
					(size 1.27 1.27)
				)
				(hide yes)
			)
		)
		(property "Description" ""
			(at 222.25 110.49 0)
			(effects
				(font
					(size 1.27 1.27)
				)
				(hide yes)
			)
		)
		(pin "1"
		)
		(instances
			(project "data-center-rdimm-ddr5-tester"
				(path ""
					(reference "#FLG011")
					(unit 1)
				)
			)
		)
	)
	(symbol
		(lib_id "antmicropower:GND")
		(at 114.3 62.23 0)
		(unit 1)
		(exclude_from_sim no)
		(in_bom yes)
		(on_board yes)
		(dnp no)
		(fields_autoplaced yes)
		(property "Reference" "#PWR0286"
			(at 114.3 68.58 0)
			(effects
				(font
					(size 1.27 1.27)
				)
				(hide yes)
			)
		)
		(property "Value" "GND"
			(at 112.395 66.675 0)
			(effects
				(font
					(size 1.27 1.27)
					(thickness 0.15)
				)
				(justify left bottom)
			)
		)
		(property "Footprint" ""
			(at 123.19 69.85 0)
			(effects
				(font
					(size 1.27 1.27)
					(thickness 0.15)
				)
				(justify left bottom)
				(hide yes)
			)
		)
		(property "Datasheet" ""
			(at 123.19 74.93 0)
			(effects
				(font
					(size 1.27 1.27)
					(thickness 0.15)
				)
				(justify left bottom)
				(hide yes)
			)
		)
		(property "Description" ""
			(at 114.3 62.23 0)
			(effects
				(font
					(size 1.27 1.27)
				)
				(hide yes)
			)
		)
		(property "Author" "Antmicro"
			(at 123.19 67.31 0)
			(effects
				(font
					(size 1.27 1.27)
					(thickness 0.15)
				)
				(justify left bottom)
				(hide yes)
			)
		)
		(property "License" "Apache-2.0"
			(at 123.19 69.85 0)
			(effects
				(font
					(size 1.27 1.27)
					(thickness 0.15)
				)
				(justify left bottom)
				(hide yes)
			)
		)
		(pin "1"
		)
		(instances
			(project "data-center-rdimm-ddr5-tester"
				(path ""
					(reference "#PWR0286")
					(unit 1)
				)
			)
		)
	)
	(symbol
		(lib_id "antmicropower:GND")
		(at 259.08 81.28 0)
		(unit 1)
		(exclude_from_sim no)
		(in_bom yes)
		(on_board yes)
		(dnp no)
		(fields_autoplaced yes)
		(property "Reference" "#PWR0342"
			(at 259.08 87.63 0)
			(effects
				(font
					(size 1.27 1.27)
				)
				(hide yes)
			)
		)
		(property "Value" "GND"
			(at 257.175 85.725 0)
			(effects
				(font
					(size 1.27 1.27)
					(thickness 0.15)
				)
				(justify left bottom)
			)
		)
		(property "Footprint" ""
			(at 267.97 88.9 0)
			(effects
				(font
					(size 1.27 1.27)
					(thickness 0.15)
				)
				(justify left bottom)
				(hide yes)
			)
		)
		(property "Datasheet" ""
			(at 267.97 93.98 0)
			(effects
				(font
					(size 1.27 1.27)
					(thickness 0.15)
				)
				(justify left bottom)
				(hide yes)
			)
		)
		(property "Description" ""
			(at 259.08 81.28 0)
			(effects
				(font
					(size 1.27 1.27)
				)
				(hide yes)
			)
		)
		(property "Author" "Antmicro"
			(at 267.97 86.36 0)
			(effects
				(font
					(size 1.27 1.27)
					(thickness 0.15)
				)
				(justify left bottom)
				(hide yes)
			)
		)
		(property "License" "Apache-2.0"
			(at 267.97 88.9 0)
			(effects
				(font
					(size 1.27 1.27)
					(thickness 0.15)
				)
				(justify left bottom)
				(hide yes)
			)
		)
		(pin "1"
		)
		(instances
			(project "data-center-rdimm-ddr5-tester"
				(path ""
					(reference "#PWR0342")
					(unit 1)
				)
			)
		)
	)
	(symbol
		(lib_id "antmicroResistors0402:R_47k_0402")
		(at 222.25 200.66 270)
		(mirror x)
		(unit 1)
		(exclude_from_sim no)
		(in_bom yes)
		(on_board yes)
		(dnp no)
		(fields_autoplaced yes)
		(property "Reference" "R210"
			(at 224.79 196.85 90)
			(effects
				(font
					(size 1.27 1.27)
				)
				(justify left)
			)
		)
		(property "Value" "R_47k_0402"
			(at 209.55 180.34 0)
			(effects
				(font
					(size 1.27 1.27)
					(thickness 0.15)
				)
				(justify left bottom)
				(hide yes)
			)
		)
		(property "Footprint" "antmicro-footprints:R_0402_1005Metric"
			(at 207.01 180.34 0)
			(effects
				(font
					(size 1.27 1.27)
					(thickness 0.15)
				)
				(justify left bottom)
				(hide yes)
			)
		)
		(property "Datasheet" "https://www.bourns.com/docs/product-datasheets/cr.pdf"
			(at 204.47 180.34 0)
			(effects
				(font
					(size 1.27 1.27)
					(thickness 0.15)
				)
				(justify left bottom)
				(hide yes)
			)
		)
		(property "Description" ""
			(at 222.25 200.66 0)
			(effects
				(font
					(size 1.27 1.27)
				)
				(hide yes)
			)
		)
		(property "Manufacturer" "Bourns"
			(at 199.39 180.34 0)
			(effects
				(font
					(size 1.27 1.27)
					(thickness 0.15)
				)
				(justify left bottom)
				(hide yes)
			)
		)
		(property "MPN" "CR0402-FX-4702GLF"
			(at 201.93 180.34 0)
			(effects
				(font
					(size 1.27 1.27)
					(thickness 0.15)
				)
				(justify left bottom)
				(hide yes)
			)
		)
		(property "Val" "47k"
			(at 224.79 199.39 90)
			(effects
				(font
					(size 1.27 1.27)
					(thickness 0.15)
				)
				(justify left)
			)
		)
		(property "License" "Apache-2.0"
			(at 196.85 180.34 0)
			(effects
				(font
					(size 1.27 1.27)
					(thickness 0.15)
				)
				(justify left bottom)
				(hide yes)
			)
		)
		(property "Author" "Antmicro"
			(at 194.31 180.34 0)
			(effects
				(font
					(size 1.27 1.27)
					(thickness 0.15)
				)
				(justify left bottom)
				(hide yes)
			)
		)
		(property "Tolerance" "1%"
			(at 212.09 180.34 0)
			(effects
				(font
					(size 1.27 1.27)
				)
				(justify left bottom)
				(hide yes)
			)
		)
		(pin "1"
		)
		(pin "2"
		)
		(instances
			(project "data-center-rdimm-ddr5-tester"
				(path ""
					(reference "R210")
					(unit 1)
				)
			)
		)
	)
	(symbol
		(lib_id "antmicroResistors0402:R_0R_0402")
		(at 259.08 96.52 90)
		(unit 1)
		(exclude_from_sim no)
		(in_bom yes)
		(on_board yes)
		(dnp no)
		(fields_autoplaced yes)
		(property "Reference" "R154"
			(at 260.985 92.7099 90)
			(effects
				(font
					(size 1.27 1.27)
				)
				(justify right)
			)
		)
		(property "Value" "R_0R_0402"
			(at 271.78 76.2 0)
			(effects
				(font
					(size 1.27 1.27)
					(thickness 0.15)
				)
				(justify left bottom)
				(hide yes)
			)
		)
		(property "Footprint" "antmicro-footprints:R_0402_1005Metric"
			(at 274.32 76.2 0)
			(effects
				(font
					(size 1.27 1.27)
					(thickness 0.15)
				)
				(justify left bottom)
				(hide yes)
			)
		)
		(property "Datasheet" "https://industrial.panasonic.com/cdbs/www-data/pdf/RDA0000/AOA0000C301.pdf"
			(at 276.86 76.2 0)
			(effects
				(font
					(size 1.27 1.27)
					(thickness 0.15)
				)
				(justify left bottom)
				(hide yes)
			)
		)
		(property "Description" ""
			(at 259.08 96.52 0)
			(effects
				(font
					(size 1.27 1.27)
				)
				(hide yes)
			)
		)
		(property "Manufacturer" "Panasonic"
			(at 281.94 76.2 0)
			(effects
				(font
					(size 1.27 1.27)
					(thickness 0.15)
				)
				(justify left bottom)
				(hide yes)
			)
		)
		(property "MPN" "ERJ2GE0R00X"
			(at 279.4 76.2 0)
			(effects
				(font
					(size 1.27 1.27)
					(thickness 0.15)
				)
				(justify left bottom)
				(hide yes)
			)
		)
		(property "Val" "0R"
			(at 260.985 95.2499 90)
			(effects
				(font
					(size 1.27 1.27)
					(thickness 0.15)
				)
				(justify right)
			)
		)
		(property "License" "Apache-2.0"
			(at 284.48 76.2 0)
			(effects
				(font
					(size 1.27 1.27)
					(thickness 0.15)
				)
				(justify left bottom)
				(hide yes)
			)
		)
		(property "Author" "Antmicro"
			(at 287.02 76.2 0)
			(effects
				(font
					(size 1.27 1.27)
					(thickness 0.15)
				)
				(justify left bottom)
				(hide yes)
			)
		)
		(property "Tolerance" "~"
			(at 269.24 76.2 0)
			(effects
				(font
					(size 1.27 1.27)
				)
				(justify left bottom)
				(hide yes)
			)
		)
		(property "Current" "1A"
			(at 260.985 96.5199 90)
			(effects
				(font
					(size 1.27 1.27)
					(thickness 0.15)
				)
				(justify right)
				(hide yes)
			)
		)
		(pin "1"
		)
		(pin "2"
		)
		(instances
			(project "data-center-rdimm-ddr5-tester"
				(path ""
					(reference "R154")
					(unit 1)
				)
			)
		)
	)
	(symbol
		(lib_id "antmicropower:GND")
		(at 120.65 81.28 0)
		(unit 1)
		(exclude_from_sim no)
		(in_bom yes)
		(on_board yes)
		(dnp no)
		(fields_autoplaced yes)
		(property "Reference" "#PWR0287"
			(at 120.65 87.63 0)
			(effects
				(font
					(size 1.27 1.27)
				)
				(hide yes)
			)
		)
		(property "Value" "GND"
			(at 118.745 85.725 0)
			(effects
				(font
					(size 1.27 1.27)
					(thickness 0.15)
				)
				(justify left bottom)
			)
		)
		(property "Footprint" ""
			(at 129.54 88.9 0)
			(effects
				(font
					(size 1.27 1.27)
					(thickness 0.15)
				)
				(justify left bottom)
				(hide yes)
			)
		)
		(property "Datasheet" ""
			(at 129.54 93.98 0)
			(effects
				(font
					(size 1.27 1.27)
					(thickness 0.15)
				)
				(justify left bottom)
				(hide yes)
			)
		)
		(property "Description" ""
			(at 120.65 81.28 0)
			(effects
				(font
					(size 1.27 1.27)
				)
				(hide yes)
			)
		)
		(property "Author" "Antmicro"
			(at 129.54 86.36 0)
			(effects
				(font
					(size 1.27 1.27)
					(thickness 0.15)
				)
				(justify left bottom)
				(hide yes)
			)
		)
		(property "License" "Apache-2.0"
			(at 129.54 88.9 0)
			(effects
				(font
					(size 1.27 1.27)
					(thickness 0.15)
				)
				(justify left bottom)
				(hide yes)
			)
		)
		(pin "1"
		)
		(instances
			(project "data-center-rdimm-ddr5-tester"
				(path ""
					(reference "#PWR0287")
					(unit 1)
				)
			)
		)
	)
	(symbol
		(lib_id "antmicroShuntsJumpers:Net-Tie_P0.127mm")
		(at 217.17 81.28 90)
		(unit 1)
		(exclude_from_sim no)
		(in_bom no)
		(on_board yes)
		(dnp no)
		(fields_autoplaced yes)
		(property "Reference" "NT10"
			(at 215.9 81.28 0)
			(effects
				(font
					(size 1.27 1.27)
				)
				(hide yes)
			)
		)
		(property "Value" "Net-Tie_P0.127mm"
			(at 224.79 59.69 0)
			(effects
				(font
					(size 1.27 1.27)
					(thickness 0.15)
				)
				(justify left bottom)
				(hide yes)
			)
		)
		(property "Footprint" "antmicro-footprints:NetTie-2_SMD_Pad0.127mm"
			(at 229.87 59.69 0)
			(effects
				(font
					(size 1.27 1.27)
					(thickness 0.15)
				)
				(justify left bottom)
				(hide yes)
			)
		)
		(property "Datasheet" ""
			(at 232.41 59.69 0)
			(effects
				(font
					(size 1.27 1.27)
					(thickness 0.15)
				)
				(justify left bottom)
				(hide yes)
			)
		)
		(property "Description" ""
			(at 217.17 81.28 0)
			(effects
				(font
					(size 1.27 1.27)
				)
				(hide yes)
			)
		)
		(property "MPN" ""
			(at 227.33 59.69 0)
			(effects
				(font
					(size 1.27 1.27)
					(thickness 0.15)
				)
				(justify left bottom)
			)
		)
		(property "Manufacturer" ""
			(at 234.95 59.69 0)
			(effects
				(font
					(size 1.27 1.27)
					(thickness 0.15)
				)
				(justify left bottom)
				(hide yes)
			)
		)
		(property "Author" "Antmicro"
			(at 237.49 59.69 0)
			(effects
				(font
					(size 1.27 1.27)
					(thickness 0.15)
				)
				(justify left bottom)
				(hide yes)
			)
		)
		(property "License" "Apache-2.0"
			(at 240.03 59.69 0)
			(effects
				(font
					(size 1.27 1.27)
					(thickness 0.15)
				)
				(justify left bottom)
				(hide yes)
			)
		)
		(pin "1"
		)
		(pin "2"
		)
		(instances
			(project "data-center-rdimm-ddr5-tester"
				(path ""
					(reference "NT10")
					(unit 1)
				)
			)
		)
	)
	(symbol
		(lib_id "antmicroResistors0402:R_100R_0402")
		(at 232.41 215.9 90)
		(unit 1)
		(exclude_from_sim no)
		(in_bom yes)
		(on_board yes)
		(dnp no)
		(fields_autoplaced yes)
		(property "Reference" "R215"
			(at 234.315 212.09 90)
			(effects
				(font
					(size 1.27 1.27)
					(thickness 0.15)
				)
				(justify right)
			)
		)
		(property "Value" "R_100R_0402"
			(at 245.11 195.58 0)
			(effects
				(font
					(size 1.27 1.27)
					(thickness 0.15)
				)
				(justify left bottom)
				(hide yes)
			)
		)
		(property "Footprint" "antmicro-footprints:R_0402_1005Metric"
			(at 247.65 195.58 0)
			(effects
				(font
					(size 1.27 1.27)
					(thickness 0.15)
				)
				(justify left bottom)
				(hide yes)
			)
		)
		(property "Datasheet" "https://www.bourns.com/docs/product-datasheets/cr.pdf"
			(at 250.19 195.58 0)
			(effects
				(font
					(size 1.27 1.27)
					(thickness 0.15)
				)
				(justify left bottom)
				(hide yes)
			)
		)
		(property "Description" ""
			(at 232.41 215.9 0)
			(effects
				(font
					(size 1.27 1.27)
				)
				(hide yes)
			)
		)
		(property "MPN" "CR0402-FX-1000GLF"
			(at 252.73 195.58 0)
			(effects
				(font
					(size 1.27 1.27)
					(thickness 0.15)
				)
				(justify left bottom)
				(hide yes)
			)
		)
		(property "Manufacturer" "Bourns"
			(at 255.27 195.58 0)
			(effects
				(font
					(size 1.27 1.27)
					(thickness 0.15)
				)
				(justify left bottom)
				(hide yes)
			)
		)
		(property "License" "Apache-2.0"
			(at 257.81 195.58 0)
			(effects
				(font
					(size 1.27 1.27)
					(thickness 0.15)
				)
				(justify left bottom)
				(hide yes)
			)
		)
		(property "Author" "Antmicro"
			(at 260.35 195.58 0)
			(effects
				(font
					(size 1.27 1.27)
					(thickness 0.15)
				)
				(justify left bottom)
				(hide yes)
			)
		)
		(property "Val" "100R"
			(at 234.315 214.63 90)
			(effects
				(font
					(size 1.27 1.27)
					(thickness 0.15)
				)
				(justify right)
			)
		)
		(property "Tolerance" "1%"
			(at 242.57 195.58 0)
			(effects
				(font
					(size 1.27 1.27)
				)
				(justify left bottom)
				(hide yes)
			)
		)
		(pin "2"
		)
		(pin "1"
		)
		(instances
			(project "data-center-rdimm-ddr5-tester"
				(path ""
					(reference "R215")
					(unit 1)
				)
			)
		)
	)
	(symbol
		(lib_id "antmicropower:PWR_FLAG")
		(at 184.15 52.07 0)
		(unit 1)
		(exclude_from_sim no)
		(in_bom yes)
		(on_board yes)
		(dnp no)
		(fields_autoplaced yes)
		(property "Reference" "#FLG04"
			(at 184.15 50.165 0)
			(effects
				(font
					(size 1.27 1.27)
				)
				(hide yes)
			)
		)
		(property "Value" "PWR_FLAG"
			(at 184.15 48.26 0)
			(effects
				(font
					(size 1.27 1.27)
				)
			)
		)
		(property "Footprint" ""
			(at 184.15 52.07 0)
			(effects
				(font
					(size 1.27 1.27)
				)
				(hide yes)
			)
		)
		(property "Datasheet" ""
			(at 184.15 52.07 0)
			(effects
				(font
					(size 1.27 1.27)
				)
				(hide yes)
			)
		)
		(property "Description" ""
			(at 184.15 52.07 0)
			(effects
				(font
					(size 1.27 1.27)
				)
				(hide yes)
			)
		)
		(pin "1"
		)
		(instances
			(project "data-center-rdimm-ddr5-tester"
				(path ""
					(reference "#FLG04")
					(unit 1)
				)
			)
		)
	)
	(symbol
		(lib_id "antmicropower:GND")
		(at 289.56 110.49 0)
		(unit 1)
		(exclude_from_sim no)
		(in_bom yes)
		(on_board yes)
		(dnp no)
		(fields_autoplaced yes)
		(property "Reference" "#PWR0394"
			(at 289.56 116.84 0)
			(effects
				(font
					(size 1.27 1.27)
				)
				(hide yes)
			)
		)
		(property "Value" "GND"
			(at 287.655 114.935 0)
			(effects
				(font
					(size 1.27 1.27)
					(thickness 0.15)
				)
				(justify left bottom)
			)
		)
		(property "Footprint" ""
			(at 298.45 118.11 0)
			(effects
				(font
					(size 1.27 1.27)
					(thickness 0.15)
				)
				(justify left bottom)
				(hide yes)
			)
		)
		(property "Datasheet" ""
			(at 298.45 123.19 0)
			(effects
				(font
					(size 1.27 1.27)
					(thickness 0.15)
				)
				(justify left bottom)
				(hide yes)
			)
		)
		(property "Description" ""
			(at 289.56 110.49 0)
			(effects
				(font
					(size 1.27 1.27)
				)
				(hide yes)
			)
		)
		(property "Author" "Antmicro"
			(at 298.45 115.57 0)
			(effects
				(font
					(size 1.27 1.27)
					(thickness 0.15)
				)
				(justify left bottom)
				(hide yes)
			)
		)
		(property "License" "Apache-2.0"
			(at 298.45 118.11 0)
			(effects
				(font
					(size 1.27 1.27)
					(thickness 0.15)
				)
				(justify left bottom)
				(hide yes)
			)
		)
		(pin "1"
		)
		(instances
			(project "data-center-rdimm-ddr5-tester"
				(path ""
					(reference "#PWR0394")
					(unit 1)
				)
			)
		)
	)
	(symbol
		(lib_id "antmicropower:GND")
		(at 259.08 109.22 0)
		(unit 1)
		(exclude_from_sim no)
		(in_bom yes)
		(on_board yes)
		(dnp no)
		(fields_autoplaced yes)
		(property "Reference" "#PWR0344"
			(at 259.08 115.57 0)
			(effects
				(font
					(size 1.27 1.27)
				)
				(hide yes)
			)
		)
		(property "Value" "GND"
			(at 257.175 113.665 0)
			(effects
				(font
					(size 1.27 1.27)
					(thickness 0.15)
				)
				(justify left bottom)
			)
		)
		(property "Footprint" ""
			(at 267.97 116.84 0)
			(effects
				(font
					(size 1.27 1.27)
					(thickness 0.15)
				)
				(justify left bottom)
				(hide yes)
			)
		)
		(property "Datasheet" ""
			(at 267.97 121.92 0)
			(effects
				(font
					(size 1.27 1.27)
					(thickness 0.15)
				)
				(justify left bottom)
				(hide yes)
			)
		)
		(property "Description" ""
			(at 259.08 109.22 0)
			(effects
				(font
					(size 1.27 1.27)
				)
				(hide yes)
			)
		)
		(property "Author" "Antmicro"
			(at 267.97 114.3 0)
			(effects
				(font
					(size 1.27 1.27)
					(thickness 0.15)
				)
				(justify left bottom)
				(hide yes)
			)
		)
		(property "License" "Apache-2.0"
			(at 267.97 116.84 0)
			(effects
				(font
					(size 1.27 1.27)
					(thickness 0.15)
				)
				(justify left bottom)
				(hide yes)
			)
		)
		(pin "1"
		)
		(instances
			(project "data-center-rdimm-ddr5-tester"
				(path ""
					(reference "#PWR0344")
					(unit 1)
				)
			)
		)
	)
	(symbol
		(lib_id "antmicroShuntsJumpers:Net-Tie_P0.127mm")
		(at 209.55 99.06 90)
		(unit 1)
		(exclude_from_sim no)
		(in_bom no)
		(on_board yes)
		(dnp no)
		(fields_autoplaced yes)
		(property "Reference" "NT3"
			(at 208.28 99.06 0)
			(effects
				(font
					(size 1.27 1.27)
				)
				(hide yes)
			)
		)
		(property "Value" "Net-Tie_P0.127mm"
			(at 217.17 77.47 0)
			(effects
				(font
					(size 1.27 1.27)
					(thickness 0.15)
				)
				(justify left bottom)
				(hide yes)
			)
		)
		(property "Footprint" "antmicro-footprints:NetTie-2_SMD_Pad0.127mm"
			(at 222.25 77.47 0)
			(effects
				(font
					(size 1.27 1.27)
					(thickness 0.15)
				)
				(justify left bottom)
				(hide yes)
			)
		)
		(property "Datasheet" ""
			(at 224.79 77.47 0)
			(effects
				(font
					(size 1.27 1.27)
					(thickness 0.15)
				)
				(justify left bottom)
				(hide yes)
			)
		)
		(property "Description" ""
			(at 209.55 99.06 0)
			(effects
				(font
					(size 1.27 1.27)
				)
				(hide yes)
			)
		)
		(property "MPN" ""
			(at 219.71 77.47 0)
			(effects
				(font
					(size 1.27 1.27)
					(thickness 0.15)
				)
				(justify left bottom)
			)
		)
		(property "Manufacturer" ""
			(at 227.33 77.47 0)
			(effects
				(font
					(size 1.27 1.27)
					(thickness 0.15)
				)
				(justify left bottom)
				(hide yes)
			)
		)
		(property "Author" "Antmicro"
			(at 229.87 77.47 0)
			(effects
				(font
					(size 1.27 1.27)
					(thickness 0.15)
				)
				(justify left bottom)
				(hide yes)
			)
		)
		(property "License" "Apache-2.0"
			(at 232.41 77.47 0)
			(effects
				(font
					(size 1.27 1.27)
					(thickness 0.15)
				)
				(justify left bottom)
				(hide yes)
			)
		)
		(pin "1"
		)
		(pin "2"
		)
		(instances
			(project "data-center-rdimm-ddr5-tester"
				(path ""
					(reference "NT3")
					(unit 1)
				)
			)
		)
	)
	(symbol
		(lib_id "antmicroTestPoints:TP_1mm_SMD")
		(at 232.41 92.71 0)
		(unit 1)
		(exclude_from_sim no)
		(in_bom no)
		(on_board yes)
		(dnp no)
		(fields_autoplaced yes)
		(property "Reference" "TP15"
			(at 236.982 93.1438 0)
			(effects
				(font
					(size 1.27 1.27)
				)
				(justify left)
			)
		)
		(property "Value" "TP_1mm_SMD"
			(at 247.65 100.33 0)
			(effects
				(font
					(size 1.27 1.27)
					(thickness 0.15)
				)
				(justify left bottom)
				(hide yes)
			)
		)
		(property "Footprint" "antmicro-footprints:TP_SMD_1mm"
			(at 247.65 102.87 0)
			(effects
				(font
					(size 1.27 1.27)
					(thickness 0.15)
				)
				(justify left bottom)
				(hide yes)
			)
		)
		(property "Datasheet" ""
			(at 247.65 105.41 0)
			(effects
				(font
					(size 1.27 1.27)
					(thickness 0.15)
				)
				(justify left bottom)
				(hide yes)
			)
		)
		(property "Description" ""
			(at 232.41 92.71 0)
			(effects
				(font
					(size 1.27 1.27)
				)
				(hide yes)
			)
		)
		(property "MPN" ""
			(at 232.41 92.71 0)
			(effects
				(font
					(size 1.27 1.27)
				)
				(hide yes)
			)
		)
		(property "Manufacturer" ""
			(at 232.41 92.71 0)
			(effects
				(font
					(size 1.27 1.27)
				)
				(hide yes)
			)
		)
		(property "Author" "Antmicro"
			(at 247.65 107.95 0)
			(effects
				(font
					(size 1.27 1.27)
					(thickness 0.15)
				)
				(justify left bottom)
				(hide yes)
			)
		)
		(property "License" "Apache-2.0"
			(at 247.65 110.49 0)
			(effects
				(font
					(size 1.27 1.27)
					(thickness 0.15)
				)
				(justify left bottom)
				(hide yes)
			)
		)
		(pin "1"
		)
		(instances
			(project "data-center-rdimm-ddr5-tester"
				(path ""
					(reference "TP15")
					(unit 1)
				)
			)
		)
	)
	(symbol
		(lib_id "antmicropower:PWR_FLAG")
		(at 220.98 91.44 0)
		(unit 1)
		(exclude_from_sim no)
		(in_bom yes)
		(on_board yes)
		(dnp no)
		(fields_autoplaced yes)
		(property "Reference" "#FLG016"
			(at 220.98 89.535 0)
			(effects
				(font
					(size 1.27 1.27)
				)
				(hide yes)
			)
		)
		(property "Value" "PWR_FLAG"
			(at 220.98 87.8642 0)
			(effects
				(font
					(size 1.27 1.27)
				)
			)
		)
		(property "Footprint" ""
			(at 220.98 91.44 0)
			(effects
				(font
					(size 1.27 1.27)
				)
				(hide yes)
			)
		)
		(property "Datasheet" ""
			(at 220.98 91.44 0)
			(effects
				(font
					(size 1.27 1.27)
				)
				(hide yes)
			)
		)
		(property "Description" ""
			(at 220.98 91.44 0)
			(effects
				(font
					(size 1.27 1.27)
				)
				(hide yes)
			)
		)
		(pin "1"
		)
		(instances
			(project "data-center-rdimm-ddr5-tester"
				(path ""
					(reference "#FLG016")
					(unit 1)
				)
			)
		)
	)
	(symbol
		(lib_id "antmicroResistors0402:R_0R_0402")
		(at 289.56 96.52 90)
		(unit 1)
		(exclude_from_sim no)
		(in_bom yes)
		(on_board yes)
		(dnp no)
		(fields_autoplaced yes)
		(property "Reference" "R165"
			(at 291.465 92.7099 90)
			(effects
				(font
					(size 1.27 1.27)
				)
				(justify right)
			)
		)
		(property "Value" "R_0R_0402"
			(at 302.26 76.2 0)
			(effects
				(font
					(size 1.27 1.27)
					(thickness 0.15)
				)
				(justify left bottom)
				(hide yes)
			)
		)
		(property "Footprint" "antmicro-footprints:R_0402_1005Metric"
			(at 304.8 76.2 0)
			(effects
				(font
					(size 1.27 1.27)
					(thickness 0.15)
				)
				(justify left bottom)
				(hide yes)
			)
		)
		(property "Datasheet" "https://industrial.panasonic.com/cdbs/www-data/pdf/RDA0000/AOA0000C301.pdf"
			(at 307.34 76.2 0)
			(effects
				(font
					(size 1.27 1.27)
					(thickness 0.15)
				)
				(justify left bottom)
				(hide yes)
			)
		)
		(property "Description" ""
			(at 289.56 96.52 0)
			(effects
				(font
					(size 1.27 1.27)
				)
				(hide yes)
			)
		)
		(property "Manufacturer" "Panasonic"
			(at 312.42 76.2 0)
			(effects
				(font
					(size 1.27 1.27)
					(thickness 0.15)
				)
				(justify left bottom)
				(hide yes)
			)
		)
		(property "MPN" "ERJ2GE0R00X"
			(at 309.88 76.2 0)
			(effects
				(font
					(size 1.27 1.27)
					(thickness 0.15)
				)
				(justify left bottom)
				(hide yes)
			)
		)
		(property "Val" "0R"
			(at 291.465 95.2499 90)
			(effects
				(font
					(size 1.27 1.27)
					(thickness 0.15)
				)
				(justify right)
			)
		)
		(property "License" "Apache-2.0"
			(at 314.96 76.2 0)
			(effects
				(font
					(size 1.27 1.27)
					(thickness 0.15)
				)
				(justify left bottom)
				(hide yes)
			)
		)
		(property "Author" "Antmicro"
			(at 317.5 76.2 0)
			(effects
				(font
					(size 1.27 1.27)
					(thickness 0.15)
				)
				(justify left bottom)
				(hide yes)
			)
		)
		(property "Tolerance" "~"
			(at 299.72 76.2 0)
			(effects
				(font
					(size 1.27 1.27)
				)
				(justify left bottom)
				(hide yes)
			)
		)
		(property "Current" "1A"
			(at 291.465 96.5199 90)
			(effects
				(font
					(size 1.27 1.27)
					(thickness 0.15)
				)
				(justify right)
				(hide yes)
			)
		)
		(pin "1"
		)
		(pin "2"
		)
		(instances
			(project "data-center-rdimm-ddr5-tester"
				(path ""
					(reference "R165")
					(unit 1)
				)
			)
		)
	)
	(symbol
		(lib_id "antmicroCapacitors0402:C_100n_0402")
		(at 185.42 220.98 270)
		(unit 1)
		(exclude_from_sim no)
		(in_bom yes)
		(on_board yes)
		(dnp no)
		(property "Reference" "C199"
			(at 184.785 221.615 90)
			(effects
				(font
					(size 1.27 1.27)
				)
				(justify right)
			)
		)
		(property "Value" "C_100n_0402"
			(at 175.26 241.3 0)
			(effects
				(font
					(size 1.27 1.27)
					(thickness 0.15)
				)
				(justify left bottom)
				(hide yes)
			)
		)
		(property "Footprint" "antmicro-footprints:C_0402_1005Metric"
			(at 172.72 241.3 0)
			(effects
				(font
					(size 1.27 1.27)
					(thickness 0.15)
				)
				(justify left bottom)
				(hide yes)
			)
		)
		(property "Datasheet" "https://www.murata.com/products/productdetail?partno=GRM155R61H104KE14%23"
			(at 170.18 241.3 0)
			(effects
				(font
					(size 1.27 1.27)
					(thickness 0.15)
				)
				(justify left bottom)
				(hide yes)
			)
		)
		(property "Description" ""
			(at 185.42 220.98 0)
			(effects
				(font
					(size 1.27 1.27)
				)
				(hide yes)
			)
		)
		(property "Manufacturer" "Murata"
			(at 165.1 241.3 0)
			(effects
				(font
					(size 1.27 1.27)
					(thickness 0.15)
				)
				(justify left bottom)
				(hide yes)
			)
		)
		(property "MPN" "GRM155R61H104KE14D"
			(at 167.64 241.3 0)
			(effects
				(font
					(size 1.27 1.27)
					(thickness 0.15)
				)
				(justify left bottom)
				(hide yes)
			)
		)
		(property "Val" "100n"
			(at 184.785 225.425 90)
			(effects
				(font
					(size 1.27 1.27)
					(thickness 0.15)
				)
				(justify right)
			)
		)
		(property "License" "Apache-2.0"
			(at 162.56 241.3 0)
			(effects
				(font
					(size 1.27 1.27)
					(thickness 0.15)
				)
				(justify left bottom)
				(hide yes)
			)
		)
		(property "Author" "Antmicro"
			(at 160.02 241.3 0)
			(effects
				(font
					(size 1.27 1.27)
					(thickness 0.15)
				)
				(justify left bottom)
				(hide yes)
			)
		)
		(property "Voltage" "50V"
			(at 157.48 241.3 0)
			(effects
				(font
					(size 1.27 1.27)
				)
				(justify left bottom)
				(hide yes)
			)
		)
		(property "Dielectric" "X5R"
			(at 154.94 241.3 0)
			(effects
				(font
					(size 1.27 1.27)
				)
				(justify left bottom)
				(hide yes)
			)
		)
		(pin "1"
		)
		(pin "2"
		)
		(instances
			(project "data-center-rdimm-ddr5-tester"
				(path ""
					(reference "C199")
					(unit 1)
				)
			)
		)
	)
	(symbol
		(lib_id "antmicroCapacitors0603:C_22u_0603")
		(at 176.53 82.55 90)
		(unit 1)
		(exclude_from_sim no)
		(in_bom yes)
		(on_board yes)
		(dnp no)
		(property "Reference" "C186"
			(at 177.165 78.105 90)
			(effects
				(font
					(size 1.27 1.27)
				)
				(justify right)
			)
		)
		(property "Value" "C_22u_0603"
			(at 186.69 62.23 0)
			(effects
				(font
					(size 1.27 1.27)
					(thickness 0.15)
				)
				(justify left bottom)
				(hide yes)
			)
		)
		(property "Footprint" "antmicro-footprints:C_0603_1608Metric"
			(at 189.23 62.23 0)
			(effects
				(font
					(size 1.27 1.27)
					(thickness 0.15)
				)
				(justify left bottom)
				(hide yes)
			)
		)
		(property "Datasheet" "https://www.murata.com/products/productdetail?partno=GRM188R60J226MEA0%23"
			(at 191.77 62.23 0)
			(effects
				(font
					(size 1.27 1.27)
					(thickness 0.15)
				)
				(justify left bottom)
				(hide yes)
			)
		)
		(property "Description" ""
			(at 176.53 82.55 0)
			(effects
				(font
					(size 1.27 1.27)
				)
				(hide yes)
			)
		)
		(property "Manufacturer" "Murata"
			(at 196.85 62.23 0)
			(effects
				(font
					(size 1.27 1.27)
					(thickness 0.15)
				)
				(justify left bottom)
				(hide yes)
			)
		)
		(property "MPN" "GRM188R60J226MEA0D"
			(at 194.31 62.23 0)
			(effects
				(font
					(size 1.27 1.27)
					(thickness 0.15)
				)
				(justify left bottom)
				(hide yes)
			)
		)
		(property "Val" "22u"
			(at 177.165 81.915 90)
			(effects
				(font
					(size 1.27 1.27)
					(thickness 0.15)
				)
				(justify right)
			)
		)
		(property "License" "Apache-2.0"
			(at 199.39 62.23 0)
			(effects
				(font
					(size 1.27 1.27)
					(thickness 0.15)
				)
				(justify left bottom)
				(hide yes)
			)
		)
		(property "Author" "Antmicro"
			(at 201.93 62.23 0)
			(effects
				(font
					(size 1.27 1.27)
					(thickness 0.15)
				)
				(justify left bottom)
				(hide yes)
			)
		)
		(property "Voltage" ""
			(at 204.47 62.23 0)
			(effects
				(font
					(size 1.27 1.27)
				)
				(justify left bottom)
				(hide yes)
			)
		)
		(property "Dielectric" ""
			(at 207.01 62.23 0)
			(effects
				(font
					(size 1.27 1.27)
				)
				(justify left bottom)
				(hide yes)
			)
		)
		(pin "1"
		)
		(pin "2"
		)
		(instances
			(project "data-center-rdimm-ddr5-tester"
				(path ""
					(reference "C186")
					(unit 1)
				)
			)
		)
	)
	(symbol
		(lib_id "antmicroShuntsJumpers:Net-Tie_P0.127mm")
		(at 209.55 81.28 90)
		(unit 1)
		(exclude_from_sim no)
		(in_bom no)
		(on_board yes)
		(dnp no)
		(fields_autoplaced yes)
		(property "Reference" "NT2"
			(at 208.28 81.28 0)
			(effects
				(font
					(size 1.27 1.27)
				)
				(hide yes)
			)
		)
		(property "Value" "Net-Tie_P0.127mm"
			(at 217.17 59.69 0)
			(effects
				(font
					(size 1.27 1.27)
					(thickness 0.15)
				)
				(justify left bottom)
				(hide yes)
			)
		)
		(property "Footprint" "antmicro-footprints:NetTie-2_SMD_Pad0.127mm"
			(at 222.25 59.69 0)
			(effects
				(font
					(size 1.27 1.27)
					(thickness 0.15)
				)
				(justify left bottom)
				(hide yes)
			)
		)
		(property "Datasheet" ""
			(at 224.79 59.69 0)
			(effects
				(font
					(size 1.27 1.27)
					(thickness 0.15)
				)
				(justify left bottom)
				(hide yes)
			)
		)
		(property "Description" ""
			(at 209.55 81.28 0)
			(effects
				(font
					(size 1.27 1.27)
				)
				(hide yes)
			)
		)
		(property "MPN" ""
			(at 219.71 59.69 0)
			(effects
				(font
					(size 1.27 1.27)
					(thickness 0.15)
				)
				(justify left bottom)
			)
		)
		(property "Manufacturer" ""
			(at 227.33 59.69 0)
			(effects
				(font
					(size 1.27 1.27)
					(thickness 0.15)
				)
				(justify left bottom)
				(hide yes)
			)
		)
		(property "Author" "Antmicro"
			(at 229.87 59.69 0)
			(effects
				(font
					(size 1.27 1.27)
					(thickness 0.15)
				)
				(justify left bottom)
				(hide yes)
			)
		)
		(property "License" "Apache-2.0"
			(at 232.41 59.69 0)
			(effects
				(font
					(size 1.27 1.27)
					(thickness 0.15)
				)
				(justify left bottom)
				(hide yes)
			)
		)
		(pin "1"
		)
		(pin "2"
		)
		(instances
			(project "data-center-rdimm-ddr5-tester"
				(path ""
					(reference "NT2")
					(unit 1)
				)
			)
		)
	)
	(symbol
		(lib_id "antmicroResistors0402:R_0R_0402")
		(at 288.29 68.58 90)
		(unit 1)
		(exclude_from_sim no)
		(in_bom yes)
		(on_board yes)
		(dnp no)
		(fields_autoplaced yes)
		(property "Reference" "R163"
			(at 290.83 64.7699 90)
			(effects
				(font
					(size 1.27 1.27)
				)
				(justify right)
			)
		)
		(property "Value" "R_0R_0402"
			(at 300.99 48.26 0)
			(effects
				(font
					(size 1.27 1.27)
					(thickness 0.15)
				)
				(justify left bottom)
				(hide yes)
			)
		)
		(property "Footprint" "antmicro-footprints:R_0402_1005Metric"
			(at 303.53 48.26 0)
			(effects
				(font
					(size 1.27 1.27)
					(thickness 0.15)
				)
				(justify left bottom)
				(hide yes)
			)
		)
		(property "Datasheet" "https://industrial.panasonic.com/cdbs/www-data/pdf/RDA0000/AOA0000C301.pdf"
			(at 306.07 48.26 0)
			(effects
				(font
					(size 1.27 1.27)
					(thickness 0.15)
				)
				(justify left bottom)
				(hide yes)
			)
		)
		(property "Description" ""
			(at 288.29 68.58 0)
			(effects
				(font
					(size 1.27 1.27)
				)
				(hide yes)
			)
		)
		(property "Manufacturer" "Panasonic"
			(at 311.15 48.26 0)
			(effects
				(font
					(size 1.27 1.27)
					(thickness 0.15)
				)
				(justify left bottom)
				(hide yes)
			)
		)
		(property "MPN" "ERJ2GE0R00X"
			(at 308.61 48.26 0)
			(effects
				(font
					(size 1.27 1.27)
					(thickness 0.15)
				)
				(justify left bottom)
				(hide yes)
			)
		)
		(property "Val" "0R"
			(at 290.83 67.3099 90)
			(effects
				(font
					(size 1.27 1.27)
					(thickness 0.15)
				)
				(justify right)
			)
		)
		(property "License" "Apache-2.0"
			(at 313.69 48.26 0)
			(effects
				(font
					(size 1.27 1.27)
					(thickness 0.15)
				)
				(justify left bottom)
				(hide yes)
			)
		)
		(property "Author" "Antmicro"
			(at 316.23 48.26 0)
			(effects
				(font
					(size 1.27 1.27)
					(thickness 0.15)
				)
				(justify left bottom)
				(hide yes)
			)
		)
		(property "Tolerance" "~"
			(at 298.45 48.26 0)
			(effects
				(font
					(size 1.27 1.27)
				)
				(justify left bottom)
				(hide yes)
			)
		)
		(property "Current" "1A"
			(at 290.83 68.5799 90)
			(effects
				(font
					(size 1.27 1.27)
					(thickness 0.15)
				)
				(justify right)
				(hide yes)
			)
		)
		(pin "1"
		)
		(pin "2"
		)
		(instances
			(project "data-center-rdimm-ddr5-tester"
				(path ""
					(reference "R163")
					(unit 1)
				)
			)
		)
	)
	(symbol
		(lib_id "antmicropower:GND")
		(at 153.67 218.44 0)
		(unit 1)
		(exclude_from_sim no)
		(in_bom yes)
		(on_board yes)
		(dnp no)
		(fields_autoplaced yes)
		(property "Reference" "#PWR0361"
			(at 153.67 224.79 0)
			(effects
				(font
					(size 1.27 1.27)
				)
				(hide yes)
			)
		)
		(property "Value" "GND"
			(at 151.765 222.885 0)
			(effects
				(font
					(size 1.27 1.27)
					(thickness 0.15)
				)
				(justify left bottom)
			)
		)
		(property "Footprint" ""
			(at 162.56 226.06 0)
			(effects
				(font
					(size 1.27 1.27)
					(thickness 0.15)
				)
				(justify left bottom)
				(hide yes)
			)
		)
		(property "Datasheet" ""
			(at 162.56 231.14 0)
			(effects
				(font
					(size 1.27 1.27)
					(thickness 0.15)
				)
				(justify left bottom)
				(hide yes)
			)
		)
		(property "Description" ""
			(at 153.67 218.44 0)
			(effects
				(font
					(size 1.27 1.27)
				)
				(hide yes)
			)
		)
		(property "Author" "Antmicro"
			(at 162.56 223.52 0)
			(effects
				(font
					(size 1.27 1.27)
					(thickness 0.15)
				)
				(justify left bottom)
				(hide yes)
			)
		)
		(property "License" "Apache-2.0"
			(at 162.56 226.06 0)
			(effects
				(font
					(size 1.27 1.27)
					(thickness 0.15)
				)
				(justify left bottom)
				(hide yes)
			)
		)
		(pin "1"
		)
		(instances
			(project "data-center-rdimm-ddr5-tester"
				(path ""
					(reference "#PWR0361")
					(unit 1)
				)
			)
		)
	)
	(symbol
		(lib_id "antmicropower:PWR_FLAG")
		(at 222.25 52.07 0)
		(unit 1)
		(exclude_from_sim no)
		(in_bom yes)
		(on_board yes)
		(dnp no)
		(fields_autoplaced yes)
		(property "Reference" "#FLG09"
			(at 222.25 50.165 0)
			(effects
				(font
					(size 1.27 1.27)
				)
				(hide yes)
			)
		)
		(property "Value" "PWR_FLAG"
			(at 222.25 48.4942 0)
			(effects
				(font
					(size 1.27 1.27)
				)
			)
		)
		(property "Footprint" ""
			(at 222.25 52.07 0)
			(effects
				(font
					(size 1.27 1.27)
				)
				(hide yes)
			)
		)
		(property "Datasheet" ""
			(at 222.25 52.07 0)
			(effects
				(font
					(size 1.27 1.27)
				)
				(hide yes)
			)
		)
		(property "Description" ""
			(at 222.25 52.07 0)
			(effects
				(font
					(size 1.27 1.27)
				)
				(hide yes)
			)
		)
		(pin "1"
		)
		(instances
			(project "data-center-rdimm-ddr5-tester"
				(path ""
					(reference "#FLG09")
					(unit 1)
				)
			)
		)
	)
	(symbol
		(lib_id "antmicropower:+3V3_AON")
		(at 185.42 220.98 0)
		(unit 1)
		(exclude_from_sim no)
		(in_bom yes)
		(on_board yes)
		(dnp no)
		(property "Reference" "#PWR0366"
			(at 185.42 224.79 0)
			(effects
				(font
					(size 1.27 1.27)
				)
				(hide yes)
			)
		)
		(property "Value" "+3V3_AON"
			(at 185.42 217.17 0)
			(effects
				(font
					(size 1.27 1.27)
				)
			)
		)
		(property "Footprint" ""
			(at 185.42 220.98 0)
			(effects
				(font
					(size 1.27 1.27)
				)
				(hide yes)
			)
		)
		(property "Datasheet" ""
			(at 185.42 220.98 0)
			(effects
				(font
					(size 1.27 1.27)
				)
				(hide yes)
			)
		)
		(property "Description" ""
			(at 185.42 220.98 0)
			(effects
				(font
					(size 1.27 1.27)
				)
				(hide yes)
			)
		)
		(pin "1"
		)
		(instances
			(project "data-center-rdimm-ddr5-tester"
				(path ""
					(reference "#PWR0366")
					(unit 1)
				)
			)
		)
	)
	(symbol
		(lib_id "antmicroResistorsmisc:R_0R01_1206")
		(at 210.82 53.34 0)
		(unit 1)
		(exclude_from_sim no)
		(in_bom yes)
		(on_board yes)
		(dnp no)
		(property "Reference" "R141"
			(at 213.36 48.26 0)
			(effects
				(font
					(size 1.27 1.27)
				)
			)
		)
		(property "Value" "R_0R01_1206"
			(at 231.14 66.04 0)
			(effects
				(font
					(size 1.27 1.27)
					(thickness 0.15)
				)
				(justify left bottom)
				(hide yes)
			)
		)
		(property "Footprint" "antmicro-footprints:R_1206_3216Metric"
			(at 231.14 68.58 0)
			(effects
				(font
					(size 1.27 1.27)
					(thickness 0.15)
				)
				(justify left bottom)
				(hide yes)
			)
		)
		(property "Datasheet" "https://www.yageo.com/upload/media/product/productsearch/datasheet/rchip/PYu-RL_Group_521_RoHS_L_2.pdf"
			(at 231.14 71.12 0)
			(effects
				(font
					(size 1.27 1.27)
					(thickness 0.15)
				)
				(justify left bottom)
				(hide yes)
			)
		)
		(property "Description" ""
			(at 210.82 53.34 0)
			(effects
				(font
					(size 1.27 1.27)
				)
				(hide yes)
			)
		)
		(property "Manufacturer" "YAGEO"
			(at 231.14 76.2 0)
			(effects
				(font
					(size 1.27 1.27)
					(thickness 0.15)
				)
				(justify left bottom)
				(hide yes)
			)
		)
		(property "MPN" "RL1206FR-7W0R01L"
			(at 231.14 73.66 0)
			(effects
				(font
					(size 1.27 1.27)
					(thickness 0.15)
				)
				(justify left bottom)
				(hide yes)
			)
		)
		(property "Val" "0R01"
			(at 213.36 50.8 0)
			(effects
				(font
					(size 1.27 1.27)
					(thickness 0.15)
				)
			)
		)
		(property "License" "Apache-2.0"
			(at 231.14 78.74 0)
			(effects
				(font
					(size 1.27 1.27)
					(thickness 0.15)
				)
				(justify left bottom)
				(hide yes)
			)
		)
		(property "Author" "Antmicro"
			(at 231.14 81.28 0)
			(effects
				(font
					(size 1.27 1.27)
					(thickness 0.15)
				)
				(justify left bottom)
				(hide yes)
			)
		)
		(property "Tolerance" "1%"
			(at 231.14 63.5 0)
			(effects
				(font
					(size 1.27 1.27)
				)
				(justify left bottom)
				(hide yes)
			)
		)
		(pin "1"
		)
		(pin "2"
		)
		(instances
			(project "data-center-rdimm-ddr5-tester"
				(path ""
					(reference "R141")
					(unit 1)
				)
			)
		)
	)
	(symbol
		(lib_id "antmicroShuntsJumpers:Net-Tie_P0.127mm")
		(at 209.55 118.11 90)
		(unit 1)
		(exclude_from_sim no)
		(in_bom no)
		(on_board yes)
		(dnp no)
		(fields_autoplaced yes)
		(property "Reference" "NT4"
			(at 208.28 118.11 0)
			(effects
				(font
					(size 1.27 1.27)
				)
				(hide yes)
			)
		)
		(property "Value" "Net-Tie_P0.127mm"
			(at 217.17 96.52 0)
			(effects
				(font
					(size 1.27 1.27)
					(thickness 0.15)
				)
				(justify left bottom)
				(hide yes)
			)
		)
		(property "Footprint" "antmicro-footprints:NetTie-2_SMD_Pad0.127mm"
			(at 222.25 96.52 0)
			(effects
				(font
					(size 1.27 1.27)
					(thickness 0.15)
				)
				(justify left bottom)
				(hide yes)
			)
		)
		(property "Datasheet" ""
			(at 224.79 96.52 0)
			(effects
				(font
					(size 1.27 1.27)
					(thickness 0.15)
				)
				(justify left bottom)
				(hide yes)
			)
		)
		(property "Description" ""
			(at 209.55 118.11 0)
			(effects
				(font
					(size 1.27 1.27)
				)
				(hide yes)
			)
		)
		(property "MPN" ""
			(at 219.71 96.52 0)
			(effects
				(font
					(size 1.27 1.27)
					(thickness 0.15)
				)
				(justify left bottom)
			)
		)
		(property "Manufacturer" ""
			(at 227.33 96.52 0)
			(effects
				(font
					(size 1.27 1.27)
					(thickness 0.15)
				)
				(justify left bottom)
				(hide yes)
			)
		)
		(property "Author" "Antmicro"
			(at 229.87 96.52 0)
			(effects
				(font
					(size 1.27 1.27)
					(thickness 0.15)
				)
				(justify left bottom)
				(hide yes)
			)
		)
		(property "License" "Apache-2.0"
			(at 232.41 96.52 0)
			(effects
				(font
					(size 1.27 1.27)
					(thickness 0.15)
				)
				(justify left bottom)
				(hide yes)
			)
		)
		(pin "1"
		)
		(pin "2"
		)
		(instances
			(project "data-center-rdimm-ddr5-tester"
				(path ""
					(reference "NT4")
					(unit 1)
				)
			)
		)
	)
	(symbol
		(lib_id "antmicropower:GND")
		(at 135.89 106.68 0)
		(unit 1)
		(exclude_from_sim no)
		(in_bom yes)
		(on_board yes)
		(dnp no)
		(fields_autoplaced yes)
		(property "Reference" "#PWR0288"
			(at 135.89 113.03 0)
			(effects
				(font
					(size 1.27 1.27)
				)
				(hide yes)
			)
		)
		(property "Value" "GND"
			(at 133.985 111.125 0)
			(effects
				(font
					(size 1.27 1.27)
					(thickness 0.15)
				)
				(justify left bottom)
			)
		)
		(property "Footprint" ""
			(at 144.78 114.3 0)
			(effects
				(font
					(size 1.27 1.27)
					(thickness 0.15)
				)
				(justify left bottom)
				(hide yes)
			)
		)
		(property "Datasheet" ""
			(at 144.78 119.38 0)
			(effects
				(font
					(size 1.27 1.27)
					(thickness 0.15)
				)
				(justify left bottom)
				(hide yes)
			)
		)
		(property "Description" ""
			(at 135.89 106.68 0)
			(effects
				(font
					(size 1.27 1.27)
				)
				(hide yes)
			)
		)
		(property "Author" "Antmicro"
			(at 144.78 111.76 0)
			(effects
				(font
					(size 1.27 1.27)
					(thickness 0.15)
				)
				(justify left bottom)
				(hide yes)
			)
		)
		(property "License" "Apache-2.0"
			(at 144.78 114.3 0)
			(effects
				(font
					(size 1.27 1.27)
					(thickness 0.15)
				)
				(justify left bottom)
				(hide yes)
			)
		)
		(pin "1"
		)
		(instances
			(project "data-center-rdimm-ddr5-tester"
				(path ""
					(reference "#PWR0288")
					(unit 1)
				)
			)
		)
	)
	(symbol
		(lib_id "antmicroCapacitorsmisc:C_22u_25V_0805")
		(at 124.46 59.69 90)
		(unit 1)
		(exclude_from_sim no)
		(in_bom yes)
		(on_board yes)
		(dnp no)
		(fields_autoplaced yes)
		(property "Reference" "C182"
			(at 128.27 54.6036 90)
			(effects
				(font
					(size 1.27 1.27)
					(thickness 0.15)
				)
				(justify right)
			)
		)
		(property "Value" "C_22u_25V_0805"
			(at 134.62 39.37 0)
			(effects
				(font
					(size 1.27 1.27)
					(thickness 0.15)
				)
				(justify left bottom)
				(hide yes)
			)
		)
		(property "Footprint" "antmicro-footprints:C_0805_2012Metric"
			(at 137.16 39.37 0)
			(effects
				(font
					(size 1.27 1.27)
					(thickness 0.15)
				)
				(justify left bottom)
				(hide yes)
			)
		)
		(property "Datasheet" "https://product.samsungsem.com/mlcc/CL21A226MAYNNN.do"
			(at 139.7 39.37 0)
			(effects
				(font
					(size 1.27 1.27)
					(thickness 0.15)
				)
				(justify left bottom)
				(hide yes)
			)
		)
		(property "Description" ""
			(at 124.46 59.69 0)
			(effects
				(font
					(size 1.27 1.27)
				)
				(hide yes)
			)
		)
		(property "MPN" "CL21A226MAYNNNE"
			(at 142.24 39.37 0)
			(effects
				(font
					(size 1.27 1.27)
					(thickness 0.15)
				)
				(justify left bottom)
				(hide yes)
			)
		)
		(property "Manufacturer" "Samsung Electro-Mechanics"
			(at 144.78 39.37 0)
			(effects
				(font
					(size 1.27 1.27)
					(thickness 0.15)
				)
				(justify left bottom)
				(hide yes)
			)
		)
		(property "License" "Apache-2.0"
			(at 147.32 39.37 0)
			(effects
				(font
					(size 1.27 1.27)
					(thickness 0.15)
				)
				(justify left bottom)
				(hide yes)
			)
		)
		(property "Author" "Antmicro"
			(at 149.86 39.37 0)
			(effects
				(font
					(size 1.27 1.27)
					(thickness 0.15)
				)
				(justify left bottom)
				(hide yes)
			)
		)
		(property "Val" "22u"
			(at 128.27 57.1436 90)
			(effects
				(font
					(size 1.27 1.27)
					(thickness 0.15)
				)
				(justify right)
			)
		)
		(property "Voltage" "25V"
			(at 128.27 59.6836 90)
			(effects
				(font
					(size 1.27 1.27)
				)
				(justify right)
			)
		)
		(property "Dielectric" "X5R"
			(at 154.94 39.37 0)
			(effects
				(font
					(size 1.27 1.27)
				)
				(justify left bottom)
				(hide yes)
			)
		)
		(property "Public" "False"
			(at 157.48 39.37 0)
			(effects
				(font
					(size 1.27 1.27)
				)
				(justify left bottom)
				(hide yes)
			)
		)
		(pin "2"
		)
		(pin "1"
		)
		(instances
			(project "data-center-rdimm-ddr5-tester"
				(path ""
					(reference "C182")
					(unit 1)
				)
			)
		)
	)
	(symbol
		(lib_id "antmicroResistorsmisc:R_0R002_0805")
		(at 210.82 74.93 0)
		(unit 1)
		(exclude_from_sim no)
		(in_bom yes)
		(on_board yes)
		(dnp no)
		(fields_autoplaced yes)
		(property "Reference" "R142"
			(at 213.36 68.58 0)
			(effects
				(font
					(size 1.27 1.27)
					(thickness 0.15)
				)
			)
		)
		(property "Value" "R_0R002_0805"
			(at 231.14 87.63 0)
			(effects
				(font
					(size 1.27 1.27)
					(thickness 0.15)
				)
				(justify left bottom)
				(hide yes)
			)
		)
		(property "Footprint" "antmicro-footprints:R_0805_2012Metric"
			(at 231.14 90.17 0)
			(effects
				(font
					(size 1.27 1.27)
					(thickness 0.15)
				)
				(justify left bottom)
				(hide yes)
			)
		)
		(property "Datasheet" "https://www2.mouser.com/datasheet/2/447/PYu_PA0100_2512_51_RoHS_2-2604383.pdf"
			(at 231.14 92.71 0)
			(effects
				(font
					(size 1.27 1.27)
					(thickness 0.15)
				)
				(justify left bottom)
				(hide yes)
			)
		)
		(property "Description" ""
			(at 210.82 74.93 0)
			(effects
				(font
					(size 1.27 1.27)
				)
				(hide yes)
			)
		)
		(property "MPN" "PA0805FRE470R002L"
			(at 231.14 95.25 0)
			(effects
				(font
					(size 1.27 1.27)
					(thickness 0.15)
				)
				(justify left bottom)
				(hide yes)
			)
		)
		(property "Manufacturer" "YAGEO"
			(at 231.14 97.79 0)
			(effects
				(font
					(size 1.27 1.27)
					(thickness 0.15)
				)
				(justify left bottom)
				(hide yes)
			)
		)
		(property "License" "Apache-2.0"
			(at 231.14 100.33 0)
			(effects
				(font
					(size 1.27 1.27)
					(thickness 0.15)
				)
				(justify left bottom)
				(hide yes)
			)
		)
		(property "Author" "Antmicro"
			(at 231.14 102.87 0)
			(effects
				(font
					(size 1.27 1.27)
					(thickness 0.15)
				)
				(justify left bottom)
				(hide yes)
			)
		)
		(property "Val" "0R002"
			(at 213.36 71.12 0)
			(effects
				(font
					(size 1.27 1.27)
					(thickness 0.15)
				)
			)
		)
		(property "Tolerance" "1%"
			(at 231.14 85.09 0)
			(effects
				(font
					(size 1.27 1.27)
				)
				(justify left bottom)
				(hide yes)
			)
		)
		(pin "2"
		)
		(pin "1"
		)
		(instances
			(project "data-center-rdimm-ddr5-tester"
				(path ""
					(reference "R142")
					(unit 1)
				)
			)
		)
	)
	(symbol
		(lib_id "antmicroPMICVoltageRegulatorsDCDCSwitchingRegulators:MPM54304GMN")
		(at 137.16 69.85 0)
		(unit 1)
		(exclude_from_sim no)
		(in_bom yes)
		(on_board yes)
		(dnp no)
		(fields_autoplaced yes)
		(property "Reference" "U19"
			(at 151.13 60.96 0)
			(effects
				(font
					(size 1.27 1.27)
					(thickness 0.15)
				)
			)
		)
		(property "Value" "MPM54304GMN"
			(at 184.15 74.93 0)
			(effects
				(font
					(size 1.27 1.27)
					(thickness 0.15)
				)
				(justify left bottom)
				(hide yes)
			)
		)
		(property "Footprint" "antmicro-footprints:LGA-33_7x7mm_P0.65mm"
			(at 184.15 77.47 0)
			(effects
				(font
					(size 1.27 1.27)
					(thickness 0.15)
				)
				(justify left bottom)
				(hide yes)
			)
		)
		(property "Datasheet" "https://www.monolithicpower.com/en/documentview/productdocument/index/version/2/document_type/Datasheet/lang/en/sku/MPM54304/document_id/4982/"
			(at 184.15 80.01 0)
			(effects
				(font
					(size 1.27 1.27)
					(thickness 0.15)
				)
				(justify left bottom)
				(hide yes)
			)
		)
		(property "Description" ""
			(at 137.16 69.85 0)
			(effects
				(font
					(size 1.27 1.27)
				)
				(hide yes)
			)
		)
		(property "MPN" "MPM54304GMN-0000"
			(at 151.13 63.5 0)
			(effects
				(font
					(size 1.27 1.27)
					(thickness 0.15)
				)
			)
		)
		(property "Manufacturer" "Monolithic Power Systems"
			(at 184.15 85.09 0)
			(effects
				(font
					(size 1.27 1.27)
					(thickness 0.15)
				)
				(justify left bottom)
				(hide yes)
			)
		)
		(property "Author" "Antmicro"
			(at 184.15 87.63 0)
			(effects
				(font
					(size 1.27 1.27)
					(thickness 0.15)
				)
				(justify left bottom)
				(hide yes)
			)
		)
		(property "License" "Apache-2.0"
			(at 184.15 90.17 0)
			(effects
				(font
					(size 1.27 1.27)
					(thickness 0.15)
				)
				(justify left bottom)
				(hide yes)
			)
		)
		(pin "31"
		)
		(pin "33"
		)
		(pin "32"
		)
		(pin "5"
		)
		(pin "26"
		)
		(pin "4"
		)
		(pin "2"
		)
		(pin "25"
		)
		(pin "22"
		)
		(pin "18"
		)
		(pin "16"
		)
		(pin "23"
		)
		(pin "17"
		)
		(pin "21"
		)
		(pin "6"
		)
		(pin "28"
		)
		(pin "29"
		)
		(pin "1"
		)
		(pin "24"
		)
		(pin "30"
		)
		(pin "20"
		)
		(pin "12"
		)
		(pin "9"
		)
		(pin "8"
		)
		(pin "3"
		)
		(pin "27"
		)
		(pin "19"
		)
		(pin "7"
		)
		(pin "13"
		)
		(pin "15"
		)
		(pin "14"
		)
		(pin "10"
		)
		(pin "11"
		)
		(instances
			(project "data-center-rdimm-ddr5-tester"
				(path ""
					(reference "U19")
					(unit 1)
				)
			)
		)
	)
	(symbol
		(lib_id "antmicroResistors0402:R_0R_0402")
		(at 146.05 215.9 90)
		(unit 1)
		(exclude_from_sim no)
		(in_bom no)
		(on_board yes)
		(dnp yes)
		(fields_autoplaced yes)
		(property "Reference" "R208"
			(at 148.59 212.09 90)
			(effects
				(font
					(size 1.27 1.27)
					(thickness 0.15)
				)
				(justify right)
			)
		)
		(property "Value" "R_0R_0402"
			(at 158.75 195.58 0)
			(effects
				(font
					(size 1.27 1.27)
					(thickness 0.15)
				)
				(justify left bottom)
				(hide yes)
			)
		)
		(property "Footprint" "antmicro-footprints:R_0402_1005Metric"
			(at 161.29 195.58 0)
			(effects
				(font
					(size 1.27 1.27)
					(thickness 0.15)
				)
				(justify left bottom)
				(hide yes)
			)
		)
		(property "Datasheet" "https://industrial.panasonic.com/cdbs/www-data/pdf/RDA0000/AOA0000C301.pdf"
			(at 163.83 195.58 0)
			(effects
				(font
					(size 1.27 1.27)
					(thickness 0.15)
				)
				(justify left bottom)
				(hide yes)
			)
		)
		(property "Description" ""
			(at 146.05 215.9 0)
			(effects
				(font
					(size 1.27 1.27)
				)
				(hide yes)
			)
		)
		(property "MPN" "ERJ2GE0R00X"
			(at 166.37 195.58 0)
			(effects
				(font
					(size 1.27 1.27)
					(thickness 0.15)
				)
				(justify left bottom)
				(hide yes)
			)
		)
		(property "Manufacturer" "Panasonic"
			(at 168.91 195.58 0)
			(effects
				(font
					(size 1.27 1.27)
					(thickness 0.15)
				)
				(justify left bottom)
				(hide yes)
			)
		)
		(property "License" "Apache-2.0"
			(at 171.45 195.58 0)
			(effects
				(font
					(size 1.27 1.27)
					(thickness 0.15)
				)
				(justify left bottom)
				(hide yes)
			)
		)
		(property "Author" "Antmicro"
			(at 173.99 195.58 0)
			(effects
				(font
					(size 1.27 1.27)
					(thickness 0.15)
				)
				(justify left bottom)
				(hide yes)
			)
		)
		(property "Val" "0R"
			(at 148.59 214.63 90)
			(effects
				(font
					(size 1.27 1.27)
					(thickness 0.15)
				)
				(justify right)
			)
		)
		(property "Tolerance" "~"
			(at 156.21 195.58 0)
			(effects
				(font
					(size 1.27 1.27)
				)
				(justify left bottom)
				(hide yes)
			)
		)
		(property "Current" "1A"
			(at 176.53 195.58 0)
			(effects
				(font
					(size 1.27 1.27)
					(thickness 0.15)
				)
				(justify left bottom)
				(hide yes)
			)
		)
		(pin "2"
		)
		(pin "1"
		)
		(instances
			(project "data-center-rdimm-ddr5-tester"
				(path ""
					(reference "R208")
					(unit 1)
				)
			)
		)
	)
	(symbol
		(lib_id "antmicroShuntsJumpers:Net-Tie_P0.127mm")
		(at 217.17 99.06 90)
		(unit 1)
		(exclude_from_sim no)
		(in_bom no)
		(on_board yes)
		(dnp no)
		(fields_autoplaced yes)
		(property "Reference" "NT11"
			(at 215.9 99.06 0)
			(effects
				(font
					(size 1.27 1.27)
				)
				(hide yes)
			)
		)
		(property "Value" "Net-Tie_P0.127mm"
			(at 224.79 77.47 0)
			(effects
				(font
					(size 1.27 1.27)
					(thickness 0.15)
				)
				(justify left bottom)
				(hide yes)
			)
		)
		(property "Footprint" "antmicro-footprints:NetTie-2_SMD_Pad0.127mm"
			(at 229.87 77.47 0)
			(effects
				(font
					(size 1.27 1.27)
					(thickness 0.15)
				)
				(justify left bottom)
				(hide yes)
			)
		)
		(property "Datasheet" ""
			(at 232.41 77.47 0)
			(effects
				(font
					(size 1.27 1.27)
					(thickness 0.15)
				)
				(justify left bottom)
				(hide yes)
			)
		)
		(property "Description" ""
			(at 217.17 99.06 0)
			(effects
				(font
					(size 1.27 1.27)
				)
				(hide yes)
			)
		)
		(property "MPN" ""
			(at 227.33 77.47 0)
			(effects
				(font
					(size 1.27 1.27)
					(thickness 0.15)
				)
				(justify left bottom)
			)
		)
		(property "Manufacturer" ""
			(at 234.95 77.47 0)
			(effects
				(font
					(size 1.27 1.27)
					(thickness 0.15)
				)
				(justify left bottom)
				(hide yes)
			)
		)
		(property "Author" "Antmicro"
			(at 237.49 77.47 0)
			(effects
				(font
					(size 1.27 1.27)
					(thickness 0.15)
				)
				(justify left bottom)
				(hide yes)
			)
		)
		(property "License" "Apache-2.0"
			(at 240.03 77.47 0)
			(effects
				(font
					(size 1.27 1.27)
					(thickness 0.15)
				)
				(justify left bottom)
				(hide yes)
			)
		)
		(pin "1"
		)
		(pin "2"
		)
		(instances
			(project "data-center-rdimm-ddr5-tester"
				(path ""
					(reference "NT11")
					(unit 1)
				)
			)
		)
	)
	(symbol
		(lib_id "antmicroCapacitors0603:C_22u_0603")
		(at 185.42 119.38 90)
		(unit 1)
		(exclude_from_sim no)
		(in_bom yes)
		(on_board yes)
		(dnp no)
		(fields_autoplaced yes)
		(property "Reference" "C260"
			(at 187.7441 116.003 90)
			(effects
				(font
					(size 1.27 1.27)
				)
				(justify right)
			)
		)
		(property "Value" "C_22u_0603"
			(at 195.58 99.06 0)
			(effects
				(font
					(size 1.27 1.27)
					(thickness 0.15)
				)
				(justify left bottom)
				(hide yes)
			)
		)
		(property "Footprint" "antmicro-footprints:C_0603_1608Metric"
			(at 198.12 99.06 0)
			(effects
				(font
					(size 1.27 1.27)
					(thickness 0.15)
				)
				(justify left bottom)
				(hide yes)
			)
		)
		(property "Datasheet" "https://www.murata.com/products/productdetail?partno=GRM188R60J226MEA0%23"
			(at 200.66 99.06 0)
			(effects
				(font
					(size 1.27 1.27)
					(thickness 0.15)
				)
				(justify left bottom)
				(hide yes)
			)
		)
		(property "Description" ""
			(at 185.42 119.38 0)
			(effects
				(font
					(size 1.27 1.27)
				)
				(hide yes)
			)
		)
		(property "Manufacturer" "Murata"
			(at 205.74 99.06 0)
			(effects
				(font
					(size 1.27 1.27)
					(thickness 0.15)
				)
				(justify left bottom)
				(hide yes)
			)
		)
		(property "MPN" "GRM188R60J226MEA0D"
			(at 203.2 99.06 0)
			(effects
				(font
					(size 1.27 1.27)
					(thickness 0.15)
				)
				(justify left bottom)
				(hide yes)
			)
		)
		(property "Val" "22u"
			(at 187.7441 118.5333 90)
			(effects
				(font
					(size 1.27 1.27)
					(thickness 0.15)
				)
				(justify right)
			)
		)
		(property "License" "Apache-2.0"
			(at 208.28 99.06 0)
			(effects
				(font
					(size 1.27 1.27)
					(thickness 0.15)
				)
				(justify left bottom)
				(hide yes)
			)
		)
		(property "Author" "Antmicro"
			(at 210.82 99.06 0)
			(effects
				(font
					(size 1.27 1.27)
					(thickness 0.15)
				)
				(justify left bottom)
				(hide yes)
			)
		)
		(property "Voltage" ""
			(at 213.36 99.06 0)
			(effects
				(font
					(size 1.27 1.27)
				)
				(justify left bottom)
				(hide yes)
			)
		)
		(property "Dielectric" ""
			(at 215.9 99.06 0)
			(effects
				(font
					(size 1.27 1.27)
				)
				(justify left bottom)
				(hide yes)
			)
		)
		(pin "1"
		)
		(pin "2"
		)
		(instances
			(project "data-center-rdimm-ddr5-tester"
				(path ""
					(reference "C260")
					(unit 1)
				)
			)
		)
	)
	(symbol
		(lib_id "antmicroCapacitors0603:C_22u_0603")
		(at 185.42 60.96 90)
		(unit 1)
		(exclude_from_sim no)
		(in_bom yes)
		(on_board yes)
		(dnp no)
		(fields_autoplaced yes)
		(property "Reference" "C187"
			(at 187.7441 57.583 90)
			(effects
				(font
					(size 1.27 1.27)
				)
				(justify right)
			)
		)
		(property "Value" "C_22u_0603"
			(at 195.58 40.64 0)
			(effects
				(font
					(size 1.27 1.27)
					(thickness 0.15)
				)
				(justify left bottom)
				(hide yes)
			)
		)
		(property "Footprint" "antmicro-footprints:C_0603_1608Metric"
			(at 198.12 40.64 0)
			(effects
				(font
					(size 1.27 1.27)
					(thickness 0.15)
				)
				(justify left bottom)
				(hide yes)
			)
		)
		(property "Datasheet" "https://www.murata.com/products/productdetail?partno=GRM188R60J226MEA0%23"
			(at 200.66 40.64 0)
			(effects
				(font
					(size 1.27 1.27)
					(thickness 0.15)
				)
				(justify left bottom)
				(hide yes)
			)
		)
		(property "Description" ""
			(at 185.42 60.96 0)
			(effects
				(font
					(size 1.27 1.27)
				)
				(hide yes)
			)
		)
		(property "Manufacturer" "Murata"
			(at 205.74 40.64 0)
			(effects
				(font
					(size 1.27 1.27)
					(thickness 0.15)
				)
				(justify left bottom)
				(hide yes)
			)
		)
		(property "MPN" "GRM188R60J226MEA0D"
			(at 203.2 40.64 0)
			(effects
				(font
					(size 1.27 1.27)
					(thickness 0.15)
				)
				(justify left bottom)
				(hide yes)
			)
		)
		(property "Val" "22u"
			(at 187.7441 60.1133 90)
			(effects
				(font
					(size 1.27 1.27)
					(thickness 0.15)
				)
				(justify right)
			)
		)
		(property "License" "Apache-2.0"
			(at 208.28 40.64 0)
			(effects
				(font
					(size 1.27 1.27)
					(thickness 0.15)
				)
				(justify left bottom)
				(hide yes)
			)
		)
		(property "Author" "Antmicro"
			(at 210.82 40.64 0)
			(effects
				(font
					(size 1.27 1.27)
					(thickness 0.15)
				)
				(justify left bottom)
				(hide yes)
			)
		)
		(property "Voltage" ""
			(at 213.36 40.64 0)
			(effects
				(font
					(size 1.27 1.27)
				)
				(justify left bottom)
				(hide yes)
			)
		)
		(property "Dielectric" ""
			(at 215.9 40.64 0)
			(effects
				(font
					(size 1.27 1.27)
				)
				(justify left bottom)
				(hide yes)
			)
		)
		(pin "1"
		)
		(pin "2"
		)
		(instances
			(project "data-center-rdimm-ddr5-tester"
				(path ""
					(reference "C187")
					(unit 1)
				)
			)
		)
	)
	(symbol
		(lib_id "antmicroShuntsJumpers:Net-Tie_P0.127mm")
		(at 217.17 59.69 90)
		(unit 1)
		(exclude_from_sim no)
		(in_bom no)
		(on_board yes)
		(dnp no)
		(fields_autoplaced yes)
		(property "Reference" "NT9"
			(at 215.9 59.69 0)
			(effects
				(font
					(size 1.27 1.27)
				)
				(hide yes)
			)
		)
		(property "Value" "Net-Tie_P0.127mm"
			(at 224.79 38.1 0)
			(effects
				(font
					(size 1.27 1.27)
					(thickness 0.15)
				)
				(justify left bottom)
				(hide yes)
			)
		)
		(property "Footprint" "antmicro-footprints:NetTie-2_SMD_Pad0.127mm"
			(at 229.87 38.1 0)
			(effects
				(font
					(size 1.27 1.27)
					(thickness 0.15)
				)
				(justify left bottom)
				(hide yes)
			)
		)
		(property "Datasheet" ""
			(at 232.41 38.1 0)
			(effects
				(font
					(size 1.27 1.27)
					(thickness 0.15)
				)
				(justify left bottom)
				(hide yes)
			)
		)
		(property "Description" ""
			(at 217.17 59.69 0)
			(effects
				(font
					(size 1.27 1.27)
				)
				(hide yes)
			)
		)
		(property "MPN" ""
			(at 227.33 38.1 0)
			(effects
				(font
					(size 1.27 1.27)
					(thickness 0.15)
				)
				(justify left bottom)
			)
		)
		(property "Manufacturer" ""
			(at 234.95 38.1 0)
			(effects
				(font
					(size 1.27 1.27)
					(thickness 0.15)
				)
				(justify left bottom)
				(hide yes)
			)
		)
		(property "Author" "Antmicro"
			(at 237.49 38.1 0)
			(effects
				(font
					(size 1.27 1.27)
					(thickness 0.15)
				)
				(justify left bottom)
				(hide yes)
			)
		)
		(property "License" "Apache-2.0"
			(at 240.03 38.1 0)
			(effects
				(font
					(size 1.27 1.27)
					(thickness 0.15)
				)
				(justify left bottom)
				(hide yes)
			)
		)
		(pin "1"
		)
		(pin "2"
		)
		(instances
			(project "data-center-rdimm-ddr5-tester"
				(path ""
					(reference "NT9")
					(unit 1)
				)
			)
		)
	)
	(symbol
		(lib_id "antmicroResistorsmisc:R_0R002_0805")
		(at 210.82 92.71 0)
		(unit 1)
		(exclude_from_sim no)
		(in_bom yes)
		(on_board yes)
		(dnp no)
		(fields_autoplaced yes)
		(property "Reference" "R144"
			(at 213.36 86.36 0)
			(effects
				(font
					(size 1.27 1.27)
					(thickness 0.15)
				)
			)
		)
		(property "Value" "R_0R002_0805"
			(at 231.14 105.41 0)
			(effects
				(font
					(size 1.27 1.27)
					(thickness 0.15)
				)
				(justify left bottom)
				(hide yes)
			)
		)
		(property "Footprint" "antmicro-footprints:R_0805_2012Metric"
			(at 231.14 107.95 0)
			(effects
				(font
					(size 1.27 1.27)
					(thickness 0.15)
				)
				(justify left bottom)
				(hide yes)
			)
		)
		(property "Datasheet" "https://www2.mouser.com/datasheet/2/447/PYu_PA0100_2512_51_RoHS_2-2604383.pdf"
			(at 231.14 110.49 0)
			(effects
				(font
					(size 1.27 1.27)
					(thickness 0.15)
				)
				(justify left bottom)
				(hide yes)
			)
		)
		(property "Description" ""
			(at 210.82 92.71 0)
			(effects
				(font
					(size 1.27 1.27)
				)
				(hide yes)
			)
		)
		(property "MPN" "PA0805FRE470R002L"
			(at 231.14 113.03 0)
			(effects
				(font
					(size 1.27 1.27)
					(thickness 0.15)
				)
				(justify left bottom)
				(hide yes)
			)
		)
		(property "Manufacturer" "YAGEO"
			(at 231.14 115.57 0)
			(effects
				(font
					(size 1.27 1.27)
					(thickness 0.15)
				)
				(justify left bottom)
				(hide yes)
			)
		)
		(property "License" "Apache-2.0"
			(at 231.14 118.11 0)
			(effects
				(font
					(size 1.27 1.27)
					(thickness 0.15)
				)
				(justify left bottom)
				(hide yes)
			)
		)
		(property "Author" "Antmicro"
			(at 231.14 120.65 0)
			(effects
				(font
					(size 1.27 1.27)
					(thickness 0.15)
				)
				(justify left bottom)
				(hide yes)
			)
		)
		(property "Val" "0R002"
			(at 213.36 88.9 0)
			(effects
				(font
					(size 1.27 1.27)
					(thickness 0.15)
				)
			)
		)
		(property "Tolerance" "1%"
			(at 231.14 102.87 0)
			(effects
				(font
					(size 1.27 1.27)
				)
				(justify left bottom)
				(hide yes)
			)
		)
		(pin "2"
		)
		(pin "1"
		)
		(instances
			(project "data-center-rdimm-ddr5-tester"
				(path ""
					(reference "R144")
					(unit 1)
				)
			)
		)
	)
	(symbol
		(lib_id "antmicropower:GND")
		(at 288.29 81.28 0)
		(unit 1)
		(exclude_from_sim no)
		(in_bom yes)
		(on_board yes)
		(dnp no)
		(fields_autoplaced yes)
		(property "Reference" "#PWR0363"
			(at 288.29 87.63 0)
			(effects
				(font
					(size 1.27 1.27)
				)
				(hide yes)
			)
		)
		(property "Value" "GND"
			(at 286.385 85.725 0)
			(effects
				(font
					(size 1.27 1.27)
					(thickness 0.15)
				)
				(justify left bottom)
			)
		)
		(property "Footprint" ""
			(at 297.18 88.9 0)
			(effects
				(font
					(size 1.27 1.27)
					(thickness 0.15)
				)
				(justify left bottom)
				(hide yes)
			)
		)
		(property "Datasheet" ""
			(at 297.18 93.98 0)
			(effects
				(font
					(size 1.27 1.27)
					(thickness 0.15)
				)
				(justify left bottom)
				(hide yes)
			)
		)
		(property "Description" ""
			(at 288.29 81.28 0)
			(effects
				(font
					(size 1.27 1.27)
				)
				(hide yes)
			)
		)
		(property "Author" "Antmicro"
			(at 297.18 86.36 0)
			(effects
				(font
					(size 1.27 1.27)
					(thickness 0.15)
				)
				(justify left bottom)
				(hide yes)
			)
		)
		(property "License" "Apache-2.0"
			(at 297.18 88.9 0)
			(effects
				(font
					(size 1.27 1.27)
					(thickness 0.15)
				)
				(justify left bottom)
				(hide yes)
			)
		)
		(pin "1"
		)
		(instances
			(project "data-center-rdimm-ddr5-tester"
				(path ""
					(reference "#PWR0363")
					(unit 1)
				)
			)
		)
	)
	(symbol
		(lib_id "antmicropower:GND")
		(at 240.03 218.44 0)
		(unit 1)
		(exclude_from_sim no)
		(in_bom yes)
		(on_board yes)
		(dnp no)
		(fields_autoplaced yes)
		(property "Reference" "#PWR0384"
			(at 240.03 224.79 0)
			(effects
				(font
					(size 1.27 1.27)
				)
				(hide yes)
			)
		)
		(property "Value" "GND"
			(at 238.125 222.885 0)
			(effects
				(font
					(size 1.27 1.27)
					(thickness 0.15)
				)
				(justify left bottom)
			)
		)
		(property "Footprint" ""
			(at 248.92 226.06 0)
			(effects
				(font
					(size 1.27 1.27)
					(thickness 0.15)
				)
				(justify left bottom)
				(hide yes)
			)
		)
		(property "Datasheet" ""
			(at 248.92 231.14 0)
			(effects
				(font
					(size 1.27 1.27)
					(thickness 0.15)
				)
				(justify left bottom)
				(hide yes)
			)
		)
		(property "Description" ""
			(at 240.03 218.44 0)
			(effects
				(font
					(size 1.27 1.27)
				)
				(hide yes)
			)
		)
		(property "Author" "Antmicro"
			(at 248.92 223.52 0)
			(effects
				(font
					(size 1.27 1.27)
					(thickness 0.15)
				)
				(justify left bottom)
				(hide yes)
			)
		)
		(property "License" "Apache-2.0"
			(at 248.92 226.06 0)
			(effects
				(font
					(size 1.27 1.27)
					(thickness 0.15)
				)
				(justify left bottom)
				(hide yes)
			)
		)
		(pin "1"
		)
		(instances
			(project "data-center-rdimm-ddr5-tester"
				(path ""
					(reference "#PWR0384")
					(unit 1)
				)
			)
		)
	)
	(symbol
		(lib_id "antmicropower:GND")
		(at 185.42 104.14 0)
		(unit 1)
		(exclude_from_sim no)
		(in_bom yes)
		(on_board yes)
		(dnp no)
		(fields_autoplaced yes)
		(property "Reference" "#PWR0305"
			(at 185.42 110.49 0)
			(effects
				(font
					(size 1.27 1.27)
				)
				(hide yes)
			)
		)
		(property "Value" "GND"
			(at 183.515 108.585 0)
			(effects
				(font
					(size 1.27 1.27)
					(thickness 0.15)
				)
				(justify left bottom)
			)
		)
		(property "Footprint" ""
			(at 194.31 111.76 0)
			(effects
				(font
					(size 1.27 1.27)
					(thickness 0.15)
				)
				(justify left bottom)
				(hide yes)
			)
		)
		(property "Datasheet" ""
			(at 194.31 116.84 0)
			(effects
				(font
					(size 1.27 1.27)
					(thickness 0.15)
				)
				(justify left bottom)
				(hide yes)
			)
		)
		(property "Description" ""
			(at 185.42 104.14 0)
			(effects
				(font
					(size 1.27 1.27)
				)
				(hide yes)
			)
		)
		(property "Author" "Antmicro"
			(at 194.31 109.22 0)
			(effects
				(font
					(size 1.27 1.27)
					(thickness 0.15)
				)
				(justify left bottom)
				(hide yes)
			)
		)
		(property "License" "Apache-2.0"
			(at 194.31 111.76 0)
			(effects
				(font
					(size 1.27 1.27)
					(thickness 0.15)
				)
				(justify left bottom)
				(hide yes)
			)
		)
		(pin "1"
		)
		(instances
			(project "data-center-rdimm-ddr5-tester"
				(path ""
					(reference "#PWR0305")
					(unit 1)
				)
			)
		)
	)
	(symbol
		(lib_id "antmicroShuntsJumpers:Net-Tie_P0.127mm")
		(at 209.55 59.69 90)
		(unit 1)
		(exclude_from_sim no)
		(in_bom no)
		(on_board yes)
		(dnp no)
		(fields_autoplaced yes)
		(property "Reference" "NT1"
			(at 208.28 59.69 0)
			(effects
				(font
					(size 1.27 1.27)
				)
				(hide yes)
			)
		)
		(property "Value" "Net-Tie_P0.127mm"
			(at 217.17 38.1 0)
			(effects
				(font
					(size 1.27 1.27)
					(thickness 0.15)
				)
				(justify left bottom)
				(hide yes)
			)
		)
		(property "Footprint" "antmicro-footprints:NetTie-2_SMD_Pad0.127mm"
			(at 222.25 38.1 0)
			(effects
				(font
					(size 1.27 1.27)
					(thickness 0.15)
				)
				(justify left bottom)
				(hide yes)
			)
		)
		(property "Datasheet" ""
			(at 224.79 38.1 0)
			(effects
				(font
					(size 1.27 1.27)
					(thickness 0.15)
				)
				(justify left bottom)
				(hide yes)
			)
		)
		(property "Description" ""
			(at 209.55 59.69 0)
			(effects
				(font
					(size 1.27 1.27)
				)
				(hide yes)
			)
		)
		(property "MPN" ""
			(at 219.71 38.1 0)
			(effects
				(font
					(size 1.27 1.27)
					(thickness 0.15)
				)
				(justify left bottom)
			)
		)
		(property "Manufacturer" ""
			(at 227.33 38.1 0)
			(effects
				(font
					(size 1.27 1.27)
					(thickness 0.15)
				)
				(justify left bottom)
				(hide yes)
			)
		)
		(property "Author" "Antmicro"
			(at 229.87 38.1 0)
			(effects
				(font
					(size 1.27 1.27)
					(thickness 0.15)
				)
				(justify left bottom)
				(hide yes)
			)
		)
		(property "License" "Apache-2.0"
			(at 232.41 38.1 0)
			(effects
				(font
					(size 1.27 1.27)
					(thickness 0.15)
				)
				(justify left bottom)
				(hide yes)
			)
		)
		(pin "1"
		)
		(pin "2"
		)
		(instances
			(project "data-center-rdimm-ddr5-tester"
				(path ""
					(reference "NT1")
					(unit 1)
				)
			)
		)
	)
	(symbol
		(lib_id "antmicroTestPoints:TP_1mm_SMD")
		(at 232.41 111.76 0)
		(unit 1)
		(exclude_from_sim no)
		(in_bom no)
		(on_board yes)
		(dnp no)
		(fields_autoplaced yes)
		(property "Reference" "TP18"
			(at 236.982 112.1938 0)
			(effects
				(font
					(size 1.27 1.27)
				)
				(justify left)
			)
		)
		(property "Value" "TP_1mm_SMD"
			(at 247.65 119.38 0)
			(effects
				(font
					(size 1.27 1.27)
					(thickness 0.15)
				)
				(justify left bottom)
				(hide yes)
			)
		)
		(property "Footprint" "antmicro-footprints:TP_SMD_1mm"
			(at 247.65 121.92 0)
			(effects
				(font
					(size 1.27 1.27)
					(thickness 0.15)
				)
				(justify left bottom)
				(hide yes)
			)
		)
		(property "Datasheet" ""
			(at 247.65 124.46 0)
			(effects
				(font
					(size 1.27 1.27)
					(thickness 0.15)
				)
				(justify left bottom)
				(hide yes)
			)
		)
		(property "Description" ""
			(at 232.41 111.76 0)
			(effects
				(font
					(size 1.27 1.27)
				)
				(hide yes)
			)
		)
		(property "MPN" ""
			(at 232.41 111.76 0)
			(effects
				(font
					(size 1.27 1.27)
				)
				(hide yes)
			)
		)
		(property "Manufacturer" ""
			(at 232.41 111.76 0)
			(effects
				(font
					(size 1.27 1.27)
				)
				(hide yes)
			)
		)
		(property "Author" "Antmicro"
			(at 247.65 127 0)
			(effects
				(font
					(size 1.27 1.27)
					(thickness 0.15)
				)
				(justify left bottom)
				(hide yes)
			)
		)
		(property "License" "Apache-2.0"
			(at 247.65 129.54 0)
			(effects
				(font
					(size 1.27 1.27)
					(thickness 0.15)
				)
				(justify left bottom)
				(hide yes)
			)
		)
		(pin "1"
		)
		(instances
			(project "data-center-rdimm-ddr5-tester"
				(path ""
					(reference "TP18")
					(unit 1)
				)
			)
		)
	)
	(symbol
		(lib_id "antmicropower:+1V8")
		(at 229.87 48.26 0)
		(unit 1)
		(exclude_from_sim no)
		(in_bom yes)
		(on_board yes)
		(dnp no)
		(fields_autoplaced yes)
		(property "Reference" "#PWR0307"
			(at 229.87 52.07 0)
			(effects
				(font
					(size 1.27 1.27)
				)
				(hide yes)
			)
		)
		(property "Value" "+1V8"
			(at 226.695 45.72 0)
			(effects
				(font
					(size 1.27 1.27)
					(thickness 0.15)
				)
				(justify left bottom)
			)
		)
		(property "Footprint" ""
			(at 245.11 55.88 0)
			(effects
				(font
					(size 1.27 1.27)
					(thickness 0.15)
				)
				(justify left bottom)
				(hide yes)
			)
		)
		(property "Datasheet" ""
			(at 245.11 58.42 0)
			(effects
				(font
					(size 1.27 1.27)
					(thickness 0.15)
				)
				(justify left bottom)
				(hide yes)
			)
		)
		(property "Description" ""
			(at 229.87 48.26 0)
			(effects
				(font
					(size 1.27 1.27)
				)
				(hide yes)
			)
		)
		(property "Author" "Antmicro"
			(at 245.11 53.34 0)
			(effects
				(font
					(size 1.27 1.27)
					(thickness 0.15)
				)
				(justify left bottom)
				(hide yes)
			)
		)
		(property "License" "Apache-2.0"
			(at 245.11 55.88 0)
			(effects
				(font
					(size 1.27 1.27)
					(thickness 0.15)
				)
				(justify left bottom)
				(hide yes)
			)
		)
		(pin "1"
		)
		(instances
			(project "data-center-rdimm-ddr5-tester"
				(path ""
					(reference "#PWR0307")
					(unit 1)
				)
			)
		)
	)
	(symbol
		(lib_id "antmicroTestPoints:TP_1mm_SMD")
		(at 231.14 74.93 0)
		(unit 1)
		(exclude_from_sim no)
		(in_bom no)
		(on_board yes)
		(dnp no)
		(property "Reference" "TP14"
			(at 236.22 74.93 0)
			(effects
				(font
					(size 1.27 1.27)
				)
				(justify left)
			)
		)
		(property "Value" "TP_1mm_SMD"
			(at 246.38 82.55 0)
			(effects
				(font
					(size 1.27 1.27)
					(thickness 0.15)
				)
				(justify left bottom)
				(hide yes)
			)
		)
		(property "Footprint" "antmicro-footprints:TP_SMD_1mm"
			(at 246.38 85.09 0)
			(effects
				(font
					(size 1.27 1.27)
					(thickness 0.15)
				)
				(justify left bottom)
				(hide yes)
			)
		)
		(property "Datasheet" ""
			(at 246.38 87.63 0)
			(effects
				(font
					(size 1.27 1.27)
					(thickness 0.15)
				)
				(justify left bottom)
				(hide yes)
			)
		)
		(property "Description" ""
			(at 231.14 74.93 0)
			(effects
				(font
					(size 1.27 1.27)
				)
				(hide yes)
			)
		)
		(property "MPN" ""
			(at 231.14 74.93 0)
			(effects
				(font
					(size 1.27 1.27)
				)
				(hide yes)
			)
		)
		(property "Manufacturer" ""
			(at 231.14 74.93 0)
			(effects
				(font
					(size 1.27 1.27)
				)
				(hide yes)
			)
		)
		(property "Author" "Antmicro"
			(at 246.38 90.17 0)
			(effects
				(font
					(size 1.27 1.27)
					(thickness 0.15)
				)
				(justify left bottom)
				(hide yes)
			)
		)
		(property "License" "Apache-2.0"
			(at 246.38 92.71 0)
			(effects
				(font
					(size 1.27 1.27)
					(thickness 0.15)
				)
				(justify left bottom)
				(hide yes)
			)
		)
		(pin "1"
		)
		(instances
			(project "data-center-rdimm-ddr5-tester"
				(path ""
					(reference "TP14")
					(unit 1)
				)
			)
		)
	)
	(symbol
		(lib_id "antmicroShuntsJumpers:Net-Tie_P0.127mm")
		(at 217.17 118.11 90)
		(unit 1)
		(exclude_from_sim no)
		(in_bom no)
		(on_board yes)
		(dnp no)
		(fields_autoplaced yes)
		(property "Reference" "NT12"
			(at 215.9 118.11 0)
			(effects
				(font
					(size 1.27 1.27)
				)
				(hide yes)
			)
		)
		(property "Value" "Net-Tie_P0.127mm"
			(at 224.79 96.52 0)
			(effects
				(font
					(size 1.27 1.27)
					(thickness 0.15)
				)
				(justify left bottom)
				(hide yes)
			)
		)
		(property "Footprint" "antmicro-footprints:NetTie-2_SMD_Pad0.127mm"
			(at 229.87 96.52 0)
			(effects
				(font
					(size 1.27 1.27)
					(thickness 0.15)
				)
				(justify left bottom)
				(hide yes)
			)
		)
		(property "Datasheet" ""
			(at 232.41 96.52 0)
			(effects
				(font
					(size 1.27 1.27)
					(thickness 0.15)
				)
				(justify left bottom)
				(hide yes)
			)
		)
		(property "Description" ""
			(at 217.17 118.11 0)
			(effects
				(font
					(size 1.27 1.27)
				)
				(hide yes)
			)
		)
		(property "MPN" ""
			(at 227.33 96.52 0)
			(effects
				(font
					(size 1.27 1.27)
					(thickness 0.15)
				)
				(justify left bottom)
			)
		)
		(property "Manufacturer" ""
			(at 234.95 96.52 0)
			(effects
				(font
					(size 1.27 1.27)
					(thickness 0.15)
				)
				(justify left bottom)
				(hide yes)
			)
		)
		(property "Author" "Antmicro"
			(at 237.49 96.52 0)
			(effects
				(font
					(size 1.27 1.27)
					(thickness 0.15)
				)
				(justify left bottom)
				(hide yes)
			)
		)
		(property "License" "Apache-2.0"
			(at 240.03 96.52 0)
			(effects
				(font
					(size 1.27 1.27)
					(thickness 0.15)
				)
				(justify left bottom)
				(hide yes)
			)
		)
		(pin "1"
		)
		(pin "2"
		)
		(instances
			(project "data-center-rdimm-ddr5-tester"
				(path ""
					(reference "NT12")
					(unit 1)
				)
			)
		)
	)
	(symbol
		(lib_id "antmicroResistors0402:R_0R_0402")
		(at 259.08 68.58 90)
		(unit 1)
		(exclude_from_sim no)
		(in_bom yes)
		(on_board yes)
		(dnp no)
		(fields_autoplaced yes)
		(property "Reference" "R152"
			(at 261.62 64.7699 90)
			(effects
				(font
					(size 1.27 1.27)
				)
				(justify right)
			)
		)
		(property "Value" "R_0R_0402"
			(at 271.78 48.26 0)
			(effects
				(font
					(size 1.27 1.27)
					(thickness 0.15)
				)
				(justify left bottom)
				(hide yes)
			)
		)
		(property "Footprint" "antmicro-footprints:R_0402_1005Metric"
			(at 274.32 48.26 0)
			(effects
				(font
					(size 1.27 1.27)
					(thickness 0.15)
				)
				(justify left bottom)
				(hide yes)
			)
		)
		(property "Datasheet" "https://industrial.panasonic.com/cdbs/www-data/pdf/RDA0000/AOA0000C301.pdf"
			(at 276.86 48.26 0)
			(effects
				(font
					(size 1.27 1.27)
					(thickness 0.15)
				)
				(justify left bottom)
				(hide yes)
			)
		)
		(property "Description" ""
			(at 259.08 68.58 0)
			(effects
				(font
					(size 1.27 1.27)
				)
				(hide yes)
			)
		)
		(property "Manufacturer" "Panasonic"
			(at 281.94 48.26 0)
			(effects
				(font
					(size 1.27 1.27)
					(thickness 0.15)
				)
				(justify left bottom)
				(hide yes)
			)
		)
		(property "MPN" "ERJ2GE0R00X"
			(at 279.4 48.26 0)
			(effects
				(font
					(size 1.27 1.27)
					(thickness 0.15)
				)
				(justify left bottom)
				(hide yes)
			)
		)
		(property "Val" "0R"
			(at 261.62 67.3099 90)
			(effects
				(font
					(size 1.27 1.27)
					(thickness 0.15)
				)
				(justify right)
			)
		)
		(property "License" "Apache-2.0"
			(at 284.48 48.26 0)
			(effects
				(font
					(size 1.27 1.27)
					(thickness 0.15)
				)
				(justify left bottom)
				(hide yes)
			)
		)
		(property "Author" "Antmicro"
			(at 287.02 48.26 0)
			(effects
				(font
					(size 1.27 1.27)
					(thickness 0.15)
				)
				(justify left bottom)
				(hide yes)
			)
		)
		(property "Tolerance" "~"
			(at 269.24 48.26 0)
			(effects
				(font
					(size 1.27 1.27)
				)
				(justify left bottom)
				(hide yes)
			)
		)
		(property "Current" "1A"
			(at 261.62 68.5799 90)
			(effects
				(font
					(size 1.27 1.27)
					(thickness 0.15)
				)
				(justify right)
				(hide yes)
			)
		)
		(pin "1"
		)
		(pin "2"
		)
		(instances
			(project "data-center-rdimm-ddr5-tester"
				(path ""
					(reference "R152")
					(unit 1)
				)
			)
		)
	)
	(symbol
		(lib_id "antmicropower:+1V8_MGTVCCAUX")
		(at 229.87 109.22 0)
		(unit 1)
		(exclude_from_sim no)
		(in_bom yes)
		(on_board yes)
		(dnp no)
		(fields_autoplaced yes)
		(property "Reference" "#PWR0336"
			(at 229.87 113.03 0)
			(effects
				(font
					(size 1.27 1.27)
				)
				(hide yes)
			)
		)
		(property "Value" "+1V8_MGTVCCAUX"
			(at 229.87 104.14 0)
			(effects
				(font
					(size 1.27 1.27)
				)
			)
		)
		(property "Footprint" ""
			(at 229.87 109.22 0)
			(effects
				(font
					(size 1.27 1.27)
				)
				(hide yes)
			)
		)
		(property "Datasheet" ""
			(at 229.87 109.22 0)
			(effects
				(font
					(size 1.27 1.27)
				)
				(hide yes)
			)
		)
		(property "Description" ""
			(at 229.87 109.22 0)
			(effects
				(font
					(size 1.27 1.27)
				)
				(hide yes)
			)
		)
		(pin "1"
		)
		(instances
			(project "data-center-rdimm-ddr5-tester"
				(path ""
					(reference "#PWR0336")
					(unit 1)
				)
			)
		)
	)
	(symbol
		(lib_id "antmicroCapacitors0603:C_22u_0603")
		(at 185.42 82.55 90)
		(unit 1)
		(exclude_from_sim no)
		(in_bom yes)
		(on_board yes)
		(dnp no)
		(fields_autoplaced yes)
		(property "Reference" "C188"
			(at 187.7441 79.173 90)
			(effects
				(font
					(size 1.27 1.27)
				)
				(justify right)
			)
		)
		(property "Value" "C_22u_0603"
			(at 195.58 62.23 0)
			(effects
				(font
					(size 1.27 1.27)
					(thickness 0.15)
				)
				(justify left bottom)
				(hide yes)
			)
		)
		(property "Footprint" "antmicro-footprints:C_0603_1608Metric"
			(at 198.12 62.23 0)
			(effects
				(font
					(size 1.27 1.27)
					(thickness 0.15)
				)
				(justify left bottom)
				(hide yes)
			)
		)
		(property "Datasheet" "https://www.murata.com/products/productdetail?partno=GRM188R60J226MEA0%23"
			(at 200.66 62.23 0)
			(effects
				(font
					(size 1.27 1.27)
					(thickness 0.15)
				)
				(justify left bottom)
				(hide yes)
			)
		)
		(property "Description" ""
			(at 185.42 82.55 0)
			(effects
				(font
					(size 1.27 1.27)
				)
				(hide yes)
			)
		)
		(property "Manufacturer" "Murata"
			(at 205.74 62.23 0)
			(effects
				(font
					(size 1.27 1.27)
					(thickness 0.15)
				)
				(justify left bottom)
				(hide yes)
			)
		)
		(property "MPN" "GRM188R60J226MEA0D"
			(at 203.2 62.23 0)
			(effects
				(font
					(size 1.27 1.27)
					(thickness 0.15)
				)
				(justify left bottom)
				(hide yes)
			)
		)
		(property "Val" "22u"
			(at 187.7441 81.7033 90)
			(effects
				(font
					(size 1.27 1.27)
					(thickness 0.15)
				)
				(justify right)
			)
		)
		(property "License" "Apache-2.0"
			(at 208.28 62.23 0)
			(effects
				(font
					(size 1.27 1.27)
					(thickness 0.15)
				)
				(justify left bottom)
				(hide yes)
			)
		)
		(property "Author" "Antmicro"
			(at 210.82 62.23 0)
			(effects
				(font
					(size 1.27 1.27)
					(thickness 0.15)
				)
				(justify left bottom)
				(hide yes)
			)
		)
		(property "Voltage" ""
			(at 213.36 62.23 0)
			(effects
				(font
					(size 1.27 1.27)
				)
				(justify left bottom)
				(hide yes)
			)
		)
		(property "Dielectric" ""
			(at 215.9 62.23 0)
			(effects
				(font
					(size 1.27 1.27)
				)
				(justify left bottom)
				(hide yes)
			)
		)
		(pin "1"
		)
		(pin "2"
		)
		(instances
			(project "data-center-rdimm-ddr5-tester"
				(path ""
					(reference "C188")
					(unit 1)
				)
			)
		)
	)
	(symbol
		(lib_id "antmicroResistors0402:R_0R_0402")
		(at 259.08 106.68 90)
		(unit 1)
		(exclude_from_sim no)
		(in_bom no)
		(on_board yes)
		(dnp yes)
		(property "Reference" "R162"
			(at 260.985 102.87 90)
			(effects
				(font
					(size 1.27 1.27)
				)
				(justify right)
			)
		)
		(property "Value" "R_0R_0402"
			(at 271.78 86.36 0)
			(effects
				(font
					(size 1.27 1.27)
					(thickness 0.15)
				)
				(justify left bottom)
				(hide yes)
			)
		)
		(property "Footprint" "antmicro-footprints:R_0402_1005Metric"
			(at 274.32 86.36 0)
			(effects
				(font
					(size 1.27 1.27)
					(thickness 0.15)
				)
				(justify left bottom)
				(hide yes)
			)
		)
		(property "Datasheet" "https://industrial.panasonic.com/cdbs/www-data/pdf/RDA0000/AOA0000C301.pdf"
			(at 276.86 86.36 0)
			(effects
				(font
					(size 1.27 1.27)
					(thickness 0.15)
				)
				(justify left bottom)
				(hide yes)
			)
		)
		(property "Description" ""
			(at 259.08 106.68 0)
			(effects
				(font
					(size 1.27 1.27)
				)
				(hide yes)
			)
		)
		(property "Manufacturer" "Panasonic"
			(at 281.94 86.36 0)
			(effects
				(font
					(size 1.27 1.27)
					(thickness 0.15)
				)
				(justify left bottom)
				(hide yes)
			)
		)
		(property "MPN" "ERJ2GE0R00X"
			(at 279.4 86.36 0)
			(effects
				(font
					(size 1.27 1.27)
					(thickness 0.15)
				)
				(justify left bottom)
				(hide yes)
			)
		)
		(property "Val" "0R"
			(at 260.985 105.41 90)
			(effects
				(font
					(size 1.27 1.27)
					(thickness 0.15)
				)
				(justify right)
			)
		)
		(property "License" "Apache-2.0"
			(at 284.48 86.36 0)
			(effects
				(font
					(size 1.27 1.27)
					(thickness 0.15)
				)
				(justify left bottom)
				(hide yes)
			)
		)
		(property "Author" "Antmicro"
			(at 287.02 86.36 0)
			(effects
				(font
					(size 1.27 1.27)
					(thickness 0.15)
				)
				(justify left bottom)
				(hide yes)
			)
		)
		(property "Tolerance" "~"
			(at 269.24 86.36 0)
			(effects
				(font
					(size 1.27 1.27)
				)
				(justify left bottom)
				(hide yes)
			)
		)
		(property "Current" "1A"
			(at 260.985 107.9499 90)
			(effects
				(font
					(size 1.27 1.27)
					(thickness 0.15)
				)
				(justify right)
				(hide yes)
			)
		)
		(pin "1"
		)
		(pin "2"
		)
		(instances
			(project "data-center-rdimm-ddr5-tester"
				(path ""
					(reference "R162")
					(unit 1)
				)
			)
		)
	)
	(symbol
		(lib_id "antmicropower:GND")
		(at 185.42 64.77 0)
		(unit 1)
		(exclude_from_sim no)
		(in_bom yes)
		(on_board yes)
		(dnp no)
		(fields_autoplaced yes)
		(property "Reference" "#PWR0295"
			(at 185.42 71.12 0)
			(effects
				(font
					(size 1.27 1.27)
				)
				(hide yes)
			)
		)
		(property "Value" "GND"
			(at 183.515 69.215 0)
			(effects
				(font
					(size 1.27 1.27)
					(thickness 0.15)
				)
				(justify left bottom)
			)
		)
		(property "Footprint" ""
			(at 194.31 72.39 0)
			(effects
				(font
					(size 1.27 1.27)
					(thickness 0.15)
				)
				(justify left bottom)
				(hide yes)
			)
		)
		(property "Datasheet" ""
			(at 194.31 77.47 0)
			(effects
				(font
					(size 1.27 1.27)
					(thickness 0.15)
				)
				(justify left bottom)
				(hide yes)
			)
		)
		(property "Description" ""
			(at 185.42 64.77 0)
			(effects
				(font
					(size 1.27 1.27)
				)
				(hide yes)
			)
		)
		(property "Author" "Antmicro"
			(at 194.31 69.85 0)
			(effects
				(font
					(size 1.27 1.27)
					(thickness 0.15)
				)
				(justify left bottom)
				(hide yes)
			)
		)
		(property "License" "Apache-2.0"
			(at 194.31 72.39 0)
			(effects
				(font
					(size 1.27 1.27)
					(thickness 0.15)
				)
				(justify left bottom)
				(hide yes)
			)
		)
		(pin "1"
		)
		(instances
			(project "data-center-rdimm-ddr5-tester"
				(path ""
					(reference "#PWR0295")
					(unit 1)
				)
			)
		)
	)
	(symbol
		(lib_id "antmicroCapacitors0402:C_1u_0402")
		(at 120.65 78.74 90)
		(unit 1)
		(exclude_from_sim no)
		(in_bom yes)
		(on_board yes)
		(dnp no)
		(fields_autoplaced yes)
		(property "Reference" "C172"
			(at 123.19 74.9235 90)
			(effects
				(font
					(size 1.27 1.27)
				)
				(justify right)
			)
		)
		(property "Value" "C_1u_0402"
			(at 124.46 78.74 0)
			(effects
				(font
					(size 1.27 1.27)
				)
				(hide yes)
			)
		)
		(property "Footprint" "antmicro-footprints:C_0402_1005Metric"
			(at 115.57 73.66 0)
			(effects
				(font
					(size 1.27 1.27)
				)
				(justify left)
				(hide yes)
			)
		)
		(property "Datasheet" "https://product.tdk.com/en/search/capacitor/ceramic/mlcc/info?part_no=C1005X6S1A105K050BC"
			(at 120.65 78.74 0)
			(effects
				(font
					(size 1.27 1.27)
				)
				(hide yes)
			)
		)
		(property "Description" ""
			(at 120.65 78.74 0)
			(effects
				(font
					(size 1.27 1.27)
				)
				(hide yes)
			)
		)
		(property "Manufacturer" "TDK"
			(at 110.49 73.66 0)
			(effects
				(font
					(size 1.27 1.27)
				)
				(justify left)
				(hide yes)
			)
		)
		(property "MPN" "C1005X6S1A105K050BC"
			(at 113.03 73.66 0)
			(effects
				(font
					(size 1.27 1.27)
				)
				(justify left)
				(hide yes)
			)
		)
		(property "Val" "1u"
			(at 123.19 77.4635 90)
			(effects
				(font
					(size 1.27 1.27)
				)
				(justify right)
			)
		)
		(property "License" "Apache-2.0"
			(at 143.51 58.42 0)
			(effects
				(font
					(size 1.27 1.27)
					(thickness 0.15)
				)
				(justify left bottom)
				(hide yes)
			)
		)
		(property "Author" "Antmicro"
			(at 146.05 58.42 0)
			(effects
				(font
					(size 1.27 1.27)
					(thickness 0.15)
				)
				(justify left bottom)
				(hide yes)
			)
		)
		(property "Voltage" ""
			(at 148.59 58.42 0)
			(effects
				(font
					(size 1.27 1.27)
				)
				(justify left bottom)
				(hide yes)
			)
		)
		(property "Dielectric" ""
			(at 151.13 58.42 0)
			(effects
				(font
					(size 1.27 1.27)
				)
				(justify left bottom)
				(hide yes)
			)
		)
		(pin "1"
		)
		(pin "2"
		)
		(instances
			(project "data-center-rdimm-ddr5-tester"
				(path ""
					(reference "C172")
					(unit 1)
				)
			)
		)
	)
	(symbol
		(lib_id "antmicroCapacitorsmisc:C_22u_25V_0805")
		(at 114.3 59.69 90)
		(unit 1)
		(exclude_from_sim no)
		(in_bom yes)
		(on_board yes)
		(dnp no)
		(fields_autoplaced yes)
		(property "Reference" "C171"
			(at 118.11 54.6036 90)
			(effects
				(font
					(size 1.27 1.27)
					(thickness 0.15)
				)
				(justify right)
			)
		)
		(property "Value" "C_22u_25V_0805"
			(at 124.46 39.37 0)
			(effects
				(font
					(size 1.27 1.27)
					(thickness 0.15)
				)
				(justify left bottom)
				(hide yes)
			)
		)
		(property "Footprint" "antmicro-footprints:C_0805_2012Metric"
			(at 127 39.37 0)
			(effects
				(font
					(size 1.27 1.27)
					(thickness 0.15)
				)
				(justify left bottom)
				(hide yes)
			)
		)
		(property "Datasheet" "https://product.samsungsem.com/mlcc/CL21A226MAYNNN.do"
			(at 129.54 39.37 0)
			(effects
				(font
					(size 1.27 1.27)
					(thickness 0.15)
				)
				(justify left bottom)
				(hide yes)
			)
		)
		(property "Description" ""
			(at 114.3 59.69 0)
			(effects
				(font
					(size 1.27 1.27)
				)
				(hide yes)
			)
		)
		(property "MPN" "CL21A226MAYNNNE"
			(at 132.08 39.37 0)
			(effects
				(font
					(size 1.27 1.27)
					(thickness 0.15)
				)
				(justify left bottom)
				(hide yes)
			)
		)
		(property "Manufacturer" "Samsung Electro-Mechanics"
			(at 134.62 39.37 0)
			(effects
				(font
					(size 1.27 1.27)
					(thickness 0.15)
				)
				(justify left bottom)
				(hide yes)
			)
		)
		(property "License" "Apache-2.0"
			(at 137.16 39.37 0)
			(effects
				(font
					(size 1.27 1.27)
					(thickness 0.15)
				)
				(justify left bottom)
				(hide yes)
			)
		)
		(property "Author" "Antmicro"
			(at 139.7 39.37 0)
			(effects
				(font
					(size 1.27 1.27)
					(thickness 0.15)
				)
				(justify left bottom)
				(hide yes)
			)
		)
		(property "Val" "22u"
			(at 118.11 57.1436 90)
			(effects
				(font
					(size 1.27 1.27)
					(thickness 0.15)
				)
				(justify right)
			)
		)
		(property "Voltage" "25V"
			(at 118.11 59.6836 90)
			(effects
				(font
					(size 1.27 1.27)
				)
				(justify right)
			)
		)
		(property "Dielectric" "X5R"
			(at 144.78 39.37 0)
			(effects
				(font
					(size 1.27 1.27)
				)
				(justify left bottom)
				(hide yes)
			)
		)
		(property "Public" "False"
			(at 147.32 39.37 0)
			(effects
				(font
					(size 1.27 1.27)
				)
				(justify left bottom)
				(hide yes)
			)
		)
		(pin "2"
		)
		(pin "1"
		)
		(instances
			(project "data-center-rdimm-ddr5-tester"
				(path ""
					(reference "C171")
					(unit 1)
				)
			)
		)
	)
	(symbol
		(lib_id "antmicroResistors0402:R_0R_0402")
		(at 259.08 78.74 90)
		(unit 1)
		(exclude_from_sim no)
		(in_bom no)
		(on_board yes)
		(dnp yes)
		(property "Reference" "R153"
			(at 261.62 74.9299 90)
			(effects
				(font
					(size 1.27 1.27)
				)
				(justify right)
			)
		)
		(property "Value" "R_0R_0402"
			(at 271.78 58.42 0)
			(effects
				(font
					(size 1.27 1.27)
					(thickness 0.15)
				)
				(justify left bottom)
				(hide yes)
			)
		)
		(property "Footprint" "antmicro-footprints:R_0402_1005Metric"
			(at 274.32 58.42 0)
			(effects
				(font
					(size 1.27 1.27)
					(thickness 0.15)
				)
				(justify left bottom)
				(hide yes)
			)
		)
		(property "Datasheet" "https://industrial.panasonic.com/cdbs/www-data/pdf/RDA0000/AOA0000C301.pdf"
			(at 276.86 58.42 0)
			(effects
				(font
					(size 1.27 1.27)
					(thickness 0.15)
				)
				(justify left bottom)
				(hide yes)
			)
		)
		(property "Description" ""
			(at 259.08 78.74 0)
			(effects
				(font
					(size 1.27 1.27)
				)
				(hide yes)
			)
		)
		(property "Manufacturer" "Panasonic"
			(at 281.94 58.42 0)
			(effects
				(font
					(size 1.27 1.27)
					(thickness 0.15)
				)
				(justify left bottom)
				(hide yes)
			)
		)
		(property "MPN" "ERJ2GE0R00X"
			(at 279.4 58.42 0)
			(effects
				(font
					(size 1.27 1.27)
					(thickness 0.15)
				)
				(justify left bottom)
				(hide yes)
			)
		)
		(property "Val" "0R"
			(at 261.62 77.4699 90)
			(effects
				(font
					(size 1.27 1.27)
					(thickness 0.15)
				)
				(justify right)
			)
		)
		(property "License" "Apache-2.0"
			(at 284.48 58.42 0)
			(effects
				(font
					(size 1.27 1.27)
					(thickness 0.15)
				)
				(justify left bottom)
				(hide yes)
			)
		)
		(property "Author" "Antmicro"
			(at 287.02 58.42 0)
			(effects
				(font
					(size 1.27 1.27)
					(thickness 0.15)
				)
				(justify left bottom)
				(hide yes)
			)
		)
		(property "Tolerance" "~"
			(at 269.24 58.42 0)
			(effects
				(font
					(size 1.27 1.27)
				)
				(justify left bottom)
				(hide yes)
			)
		)
		(property "Current" "1A"
			(at 261.62 80.0099 90)
			(effects
				(font
					(size 1.27 1.27)
					(thickness 0.15)
				)
				(justify right)
				(hide yes)
			)
		)
		(pin "1"
		)
		(pin "2"
		)
		(instances
			(project "data-center-rdimm-ddr5-tester"
				(path ""
					(reference "R153")
					(unit 1)
				)
			)
		)
	)
	(symbol
		(lib_id "antmicropower:GND")
		(at 271.78 226.06 0)
		(unit 1)
		(exclude_from_sim no)
		(in_bom yes)
		(on_board yes)
		(dnp no)
		(fields_autoplaced yes)
		(property "Reference" "#PWR0387"
			(at 271.78 232.41 0)
			(effects
				(font
					(size 1.27 1.27)
				)
				(hide yes)
			)
		)
		(property "Value" "GND"
			(at 269.875 230.505 0)
			(effects
				(font
					(size 1.27 1.27)
					(thickness 0.15)
				)
				(justify left bottom)
			)
		)
		(property "Footprint" ""
			(at 280.67 233.68 0)
			(effects
				(font
					(size 1.27 1.27)
					(thickness 0.15)
				)
				(justify left bottom)
				(hide yes)
			)
		)
		(property "Datasheet" ""
			(at 280.67 238.76 0)
			(effects
				(font
					(size 1.27 1.27)
					(thickness 0.15)
				)
				(justify left bottom)
				(hide yes)
			)
		)
		(property "Description" ""
			(at 271.78 226.06 0)
			(effects
				(font
					(size 1.27 1.27)
				)
				(hide yes)
			)
		)
		(property "Author" "Antmicro"
			(at 280.67 231.14 0)
			(effects
				(font
					(size 1.27 1.27)
					(thickness 0.15)
				)
				(justify left bottom)
				(hide yes)
			)
		)
		(property "License" "Apache-2.0"
			(at 280.67 233.68 0)
			(effects
				(font
					(size 1.27 1.27)
					(thickness 0.15)
				)
				(justify left bottom)
				(hide yes)
			)
		)
		(pin "1"
		)
		(instances
			(project "data-center-rdimm-ddr5-tester"
				(path ""
					(reference "#PWR0387")
					(unit 1)
				)
			)
		)
	)
	(symbol
		(lib_id "antmicroResistors0402:R_0R_0402")
		(at 289.56 106.68 90)
		(unit 1)
		(exclude_from_sim no)
		(in_bom no)
		(on_board yes)
		(dnp yes)
		(property "Reference" "R207"
			(at 291.465 102.87 90)
			(effects
				(font
					(size 1.27 1.27)
				)
				(justify right)
			)
		)
		(property "Value" "R_0R_0402"
			(at 302.26 86.36 0)
			(effects
				(font
					(size 1.27 1.27)
					(thickness 0.15)
				)
				(justify left bottom)
				(hide yes)
			)
		)
		(property "Footprint" "antmicro-footprints:R_0402_1005Metric"
			(at 304.8 86.36 0)
			(effects
				(font
					(size 1.27 1.27)
					(thickness 0.15)
				)
				(justify left bottom)
				(hide yes)
			)
		)
		(property "Datasheet" "https://industrial.panasonic.com/cdbs/www-data/pdf/RDA0000/AOA0000C301.pdf"
			(at 307.34 86.36 0)
			(effects
				(font
					(size 1.27 1.27)
					(thickness 0.15)
				)
				(justify left bottom)
				(hide yes)
			)
		)
		(property "Description" ""
			(at 289.56 106.68 0)
			(effects
				(font
					(size 1.27 1.27)
				)
				(hide yes)
			)
		)
		(property "Manufacturer" "Panasonic"
			(at 312.42 86.36 0)
			(effects
				(font
					(size 1.27 1.27)
					(thickness 0.15)
				)
				(justify left bottom)
				(hide yes)
			)
		)
		(property "MPN" "ERJ2GE0R00X"
			(at 309.88 86.36 0)
			(effects
				(font
					(size 1.27 1.27)
					(thickness 0.15)
				)
				(justify left bottom)
				(hide yes)
			)
		)
		(property "Val" "0R"
			(at 291.465 105.41 90)
			(effects
				(font
					(size 1.27 1.27)
					(thickness 0.15)
				)
				(justify right)
			)
		)
		(property "License" "Apache-2.0"
			(at 314.96 86.36 0)
			(effects
				(font
					(size 1.27 1.27)
					(thickness 0.15)
				)
				(justify left bottom)
				(hide yes)
			)
		)
		(property "Author" "Antmicro"
			(at 317.5 86.36 0)
			(effects
				(font
					(size 1.27 1.27)
					(thickness 0.15)
				)
				(justify left bottom)
				(hide yes)
			)
		)
		(property "Tolerance" "~"
			(at 299.72 86.36 0)
			(effects
				(font
					(size 1.27 1.27)
				)
				(justify left bottom)
				(hide yes)
			)
		)
		(property "Current" "1A"
			(at 291.465 107.9499 90)
			(effects
				(font
					(size 1.27 1.27)
					(thickness 0.15)
				)
				(justify right)
				(hide yes)
			)
		)
		(pin "1"
		)
		(pin "2"
		)
		(instances
			(project "data-center-rdimm-ddr5-tester"
				(path ""
					(reference "R207")
					(unit 1)
				)
			)
		)
	)
	(symbol
		(lib_id "antmicropower:+3V3_AON")
		(at 222.25 190.5 0)
		(unit 1)
		(exclude_from_sim no)
		(in_bom yes)
		(on_board yes)
		(dnp no)
		(property "Reference" "#PWR0370"
			(at 222.25 194.31 0)
			(effects
				(font
					(size 1.27 1.27)
				)
				(hide yes)
			)
		)
		(property "Value" "+3V3_AON"
			(at 222.25 186.69 0)
			(effects
				(font
					(size 1.27 1.27)
				)
			)
		)
		(property "Footprint" ""
			(at 222.25 190.5 0)
			(effects
				(font
					(size 1.27 1.27)
				)
				(hide yes)
			)
		)
		(property "Datasheet" ""
			(at 222.25 190.5 0)
			(effects
				(font
					(size 1.27 1.27)
				)
				(hide yes)
			)
		)
		(property "Description" ""
			(at 222.25 190.5 0)
			(effects
				(font
					(size 1.27 1.27)
				)
				(hide yes)
			)
		)
		(pin "1"
		)
		(instances
			(project "data-center-rdimm-ddr5-tester"
				(path ""
					(reference "#PWR0370")
					(unit 1)
				)
			)
		)
	)
	(symbol
		(lib_id "antmicropower:GND")
		(at 185.42 226.06 0)
		(unit 1)
		(exclude_from_sim no)
		(in_bom yes)
		(on_board yes)
		(dnp no)
		(fields_autoplaced yes)
		(property "Reference" "#PWR0367"
			(at 185.42 232.41 0)
			(effects
				(font
					(size 1.27 1.27)
				)
				(hide yes)
			)
		)
		(property "Value" "GND"
			(at 183.515 230.505 0)
			(effects
				(font
					(size 1.27 1.27)
					(thickness 0.15)
				)
				(justify left bottom)
			)
		)
		(property "Footprint" ""
			(at 194.31 233.68 0)
			(effects
				(font
					(size 1.27 1.27)
					(thickness 0.15)
				)
				(justify left bottom)
				(hide yes)
			)
		)
		(property "Datasheet" ""
			(at 194.31 238.76 0)
			(effects
				(font
					(size 1.27 1.27)
					(thickness 0.15)
				)
				(justify left bottom)
				(hide yes)
			)
		)
		(property "Description" ""
			(at 185.42 226.06 0)
			(effects
				(font
					(size 1.27 1.27)
				)
				(hide yes)
			)
		)
		(property "Author" "Antmicro"
			(at 194.31 231.14 0)
			(effects
				(font
					(size 1.27 1.27)
					(thickness 0.15)
				)
				(justify left bottom)
				(hide yes)
			)
		)
		(property "License" "Apache-2.0"
			(at 194.31 233.68 0)
			(effects
				(font
					(size 1.27 1.27)
					(thickness 0.15)
				)
				(justify left bottom)
				(hide yes)
			)
		)
		(pin "1"
		)
		(instances
			(project "data-center-rdimm-ddr5-tester"
				(path ""
					(reference "#PWR0367")
					(unit 1)
				)
			)
		)
	)
	(symbol
		(lib_id "antmicropower:+3V3_AON")
		(at 135.89 190.5 0)
		(unit 1)
		(exclude_from_sim no)
		(in_bom yes)
		(on_board yes)
		(dnp no)
		(property "Reference" "#PWR0360"
			(at 135.89 194.31 0)
			(effects
				(font
					(size 1.27 1.27)
				)
				(hide yes)
			)
		)
		(property "Value" "+3V3_AON"
			(at 135.89 186.69 0)
			(effects
				(font
					(size 1.27 1.27)
				)
			)
		)
		(property "Footprint" ""
			(at 135.89 190.5 0)
			(effects
				(font
					(size 1.27 1.27)
				)
				(hide yes)
			)
		)
		(property "Datasheet" ""
			(at 135.89 190.5 0)
			(effects
				(font
					(size 1.27 1.27)
				)
				(hide yes)
			)
		)
		(property "Description" ""
			(at 135.89 190.5 0)
			(effects
				(font
					(size 1.27 1.27)
				)
				(hide yes)
			)
		)
		(pin "1"
		)
		(instances
			(project "data-center-rdimm-ddr5-tester"
				(path ""
					(reference "#PWR0360")
					(unit 1)
				)
			)
		)
	)
	(symbol
		(lib_id "antmicroCapacitors0402:C_100n_0402")
		(at 271.78 220.98 270)
		(unit 1)
		(exclude_from_sim no)
		(in_bom yes)
		(on_board yes)
		(dnp no)
		(fields_autoplaced yes)
		(property "Reference" "C214"
			(at 269.24 222.2563 90)
			(effects
				(font
					(size 1.27 1.27)
				)
				(justify right)
			)
		)
		(property "Value" "C_100n_0402"
			(at 261.62 241.3 0)
			(effects
				(font
					(size 1.27 1.27)
					(thickness 0.15)
				)
				(justify left bottom)
				(hide yes)
			)
		)
		(property "Footprint" "antmicro-footprints:C_0402_1005Metric"
			(at 259.08 241.3 0)
			(effects
				(font
					(size 1.27 1.27)
					(thickness 0.15)
				)
				(justify left bottom)
				(hide yes)
			)
		)
		(property "Datasheet" "https://www.murata.com/products/productdetail?partno=GRM155R61H104KE14%23"
			(at 256.54 241.3 0)
			(effects
				(font
					(size 1.27 1.27)
					(thickness 0.15)
				)
				(justify left bottom)
				(hide yes)
			)
		)
		(property "Description" ""
			(at 271.78 220.98 0)
			(effects
				(font
					(size 1.27 1.27)
				)
				(hide yes)
			)
		)
		(property "Manufacturer" "Murata"
			(at 251.46 241.3 0)
			(effects
				(font
					(size 1.27 1.27)
					(thickness 0.15)
				)
				(justify left bottom)
				(hide yes)
			)
		)
		(property "MPN" "GRM155R61H104KE14D"
			(at 254 241.3 0)
			(effects
				(font
					(size 1.27 1.27)
					(thickness 0.15)
				)
				(justify left bottom)
				(hide yes)
			)
		)
		(property "Val" "100n"
			(at 269.24 225.4312 90)
			(effects
				(font
					(size 1.27 1.27)
					(thickness 0.15)
				)
				(justify right)
			)
		)
		(property "License" "Apache-2.0"
			(at 248.92 241.3 0)
			(effects
				(font
					(size 1.27 1.27)
					(thickness 0.15)
				)
				(justify left bottom)
				(hide yes)
			)
		)
		(property "Author" "Antmicro"
			(at 246.38 241.3 0)
			(effects
				(font
					(size 1.27 1.27)
					(thickness 0.15)
				)
				(justify left bottom)
				(hide yes)
			)
		)
		(property "Voltage" "50V"
			(at 243.84 241.3 0)
			(effects
				(font
					(size 1.27 1.27)
				)
				(justify left bottom)
				(hide yes)
			)
		)
		(property "Dielectric" "X5R"
			(at 241.3 241.3 0)
			(effects
				(font
					(size 1.27 1.27)
				)
				(justify left bottom)
				(hide yes)
			)
		)
		(pin "1"
		)
		(pin "2"
		)
		(instances
			(project "data-center-rdimm-ddr5-tester"
				(path ""
					(reference "C214")
					(unit 1)
				)
			)
		)
	)
	(symbol
		(lib_id "antmicropower:+3V3_AON")
		(at 271.78 219.71 0)
		(unit 1)
		(exclude_from_sim no)
		(in_bom yes)
		(on_board yes)
		(dnp no)
		(property "Reference" "#PWR0385"
			(at 271.78 223.52 0)
			(effects
				(font
					(size 1.27 1.27)
				)
				(hide yes)
			)
		)
		(property "Value" "+3V3_AON"
			(at 271.78 215.9 0)
			(effects
				(font
					(size 1.27 1.27)
				)
			)
		)
		(property "Footprint" ""
			(at 271.78 219.71 0)
			(effects
				(font
					(size 1.27 1.27)
				)
				(hide yes)
			)
		)
		(property "Datasheet" ""
			(at 271.78 219.71 0)
			(effects
				(font
					(size 1.27 1.27)
				)
				(hide yes)
			)
		)
		(property "Description" ""
			(at 271.78 219.71 0)
			(effects
				(font
					(size 1.27 1.27)
				)
				(hide yes)
			)
		)
		(pin "1"
		)
		(instances
			(project "data-center-rdimm-ddr5-tester"
				(path ""
					(reference "#PWR0385")
					(unit 1)
				)
			)
		)
	)
	(symbol
		(lib_id "antmicroCapacitors0603:C_22u_0603")
		(at 176.53 60.96 90)
		(unit 1)
		(exclude_from_sim no)
		(in_bom yes)
		(on_board yes)
		(dnp no)
		(property "Reference" "C183"
			(at 177.165 56.515 90)
			(effects
				(font
					(size 1.27 1.27)
				)
				(justify right)
			)
		)
		(property "Value" "C_22u_0603"
			(at 186.69 40.64 0)
			(effects
				(font
					(size 1.27 1.27)
					(thickness 0.15)
				)
				(justify left bottom)
				(hide yes)
			)
		)
		(property "Footprint" "antmicro-footprints:C_0603_1608Metric"
			(at 189.23 40.64 0)
			(effects
				(font
					(size 1.27 1.27)
					(thickness 0.15)
				)
				(justify left bottom)
				(hide yes)
			)
		)
		(property "Datasheet" "https://www.murata.com/products/productdetail?partno=GRM188R60J226MEA0%23"
			(at 191.77 40.64 0)
			(effects
				(font
					(size 1.27 1.27)
					(thickness 0.15)
				)
				(justify left bottom)
				(hide yes)
			)
		)
		(property "Description" ""
			(at 176.53 60.96 0)
			(effects
				(font
					(size 1.27 1.27)
				)
				(hide yes)
			)
		)
		(property "Manufacturer" "Murata"
			(at 196.85 40.64 0)
			(effects
				(font
					(size 1.27 1.27)
					(thickness 0.15)
				)
				(justify left bottom)
				(hide yes)
			)
		)
		(property "MPN" "GRM188R60J226MEA0D"
			(at 194.31 40.64 0)
			(effects
				(font
					(size 1.27 1.27)
					(thickness 0.15)
				)
				(justify left bottom)
				(hide yes)
			)
		)
		(property "Val" "22u"
			(at 177.165 60.325 90)
			(effects
				(font
					(size 1.27 1.27)
					(thickness 0.15)
				)
				(justify right)
			)
		)
		(property "License" "Apache-2.0"
			(at 199.39 40.64 0)
			(effects
				(font
					(size 1.27 1.27)
					(thickness 0.15)
				)
				(justify left bottom)
				(hide yes)
			)
		)
		(property "Author" "Antmicro"
			(at 201.93 40.64 0)
			(effects
				(font
					(size 1.27 1.27)
					(thickness 0.15)
				)
				(justify left bottom)
				(hide yes)
			)
		)
		(property "Voltage" ""
			(at 204.47 40.64 0)
			(effects
				(font
					(size 1.27 1.27)
				)
				(justify left bottom)
				(hide yes)
			)
		)
		(property "Dielectric" ""
			(at 207.01 40.64 0)
			(effects
				(font
					(size 1.27 1.27)
				)
				(justify left bottom)
				(hide yes)
			)
		)
		(pin "1"
		)
		(pin "2"
		)
		(instances
			(project "data-center-rdimm-ddr5-tester"
				(path ""
					(reference "C183")
					(unit 1)
				)
			)
		)
	)
	(symbol
		(lib_id "antmicroResistorsmisc:R_0R01_1206")
		(at 210.82 111.76 0)
		(unit 1)
		(exclude_from_sim no)
		(in_bom yes)
		(on_board yes)
		(dnp no)
		(property "Reference" "R151"
			(at 213.36 106.68 0)
			(effects
				(font
					(size 1.27 1.27)
				)
			)
		)
		(property "Value" "R_0R01_1206"
			(at 231.14 124.46 0)
			(effects
				(font
					(size 1.27 1.27)
					(thickness 0.15)
				)
				(justify left bottom)
				(hide yes)
			)
		)
		(property "Footprint" "antmicro-footprints:R_1206_3216Metric"
			(at 231.14 127 0)
			(effects
				(font
					(size 1.27 1.27)
					(thickness 0.15)
				)
				(justify left bottom)
				(hide yes)
			)
		)
		(property "Datasheet" "https://www.yageo.com/upload/media/product/productsearch/datasheet/rchip/PYu-RL_Group_521_RoHS_L_2.pdf"
			(at 231.14 129.54 0)
			(effects
				(font
					(size 1.27 1.27)
					(thickness 0.15)
				)
				(justify left bottom)
				(hide yes)
			)
		)
		(property "Description" ""
			(at 210.82 111.76 0)
			(effects
				(font
					(size 1.27 1.27)
				)
				(hide yes)
			)
		)
		(property "Manufacturer" "YAGEO"
			(at 231.14 134.62 0)
			(effects
				(font
					(size 1.27 1.27)
					(thickness 0.15)
				)
				(justify left bottom)
				(hide yes)
			)
		)
		(property "MPN" "RL1206FR-7W0R01L"
			(at 231.14 132.08 0)
			(effects
				(font
					(size 1.27 1.27)
					(thickness 0.15)
				)
				(justify left bottom)
				(hide yes)
			)
		)
		(property "Val" "0R01"
			(at 213.36 109.22 0)
			(effects
				(font
					(size 1.27 1.27)
					(thickness 0.15)
				)
			)
		)
		(property "License" "Apache-2.0"
			(at 231.14 137.16 0)
			(effects
				(font
					(size 1.27 1.27)
					(thickness 0.15)
				)
				(justify left bottom)
				(hide yes)
			)
		)
		(property "Author" "Antmicro"
			(at 231.14 139.7 0)
			(effects
				(font
					(size 1.27 1.27)
					(thickness 0.15)
				)
				(justify left bottom)
				(hide yes)
			)
		)
		(property "Tolerance" "1%"
			(at 231.14 121.92 0)
			(effects
				(font
					(size 1.27 1.27)
				)
				(justify left bottom)
				(hide yes)
			)
		)
		(pin "1"
		)
		(pin "2"
		)
		(instances
			(project "data-center-rdimm-ddr5-tester"
				(path ""
					(reference "R151")
					(unit 1)
				)
			)
		)
	)
)
